FILE_TYPE = MACRO_DRAWING;
SET COLOR_WIRE YELLOW;
SET COLOR_PROP MONO;
SET COLOR_DOT WHITE;
SET COLOR_ARC YELLOW;
SET COLOR_BODY GREEN;
SET COLOR_NOTE MONO;
SET PROP_DISPLAY VALUE;
SET PAGE_NUMBER P46;
FORCEADD GND..1
(-2975 650);
FORCEPROP 3 LASTPIN (-2975 700) SIG_NAME GND\g
J 0
(-2965 710);
DISPLAY 0.659574 (-2965 710);
PAINT MONO (-2965 710);
DISPLAY INVISIBLE (-2965 710);
FORCEPROP 1 LAST VOLTAGE 0
J 0
(-2975 650);
PAINT SKYBLUE (-2975 650);
DISPLAY INVISIBLE (-2975 650);
FORCEPROP 2 LAST BOM_COST MEM
J 0
(-2975 655);
PAINT ORANGE (-2975 655);
DISPLAY INVISIBLE (-2975 655);
FORCEPROP 1 LAST SIZE 1B
J 0
(-2900 600);
DISPLAY 1.787234 (-2900 600);
PAINT GREEN (-2900 600);
DISPLAY INVISIBLE (-2900 600);
FORCEPROP 2 LAST CDS_LIB mstr_symbols
J 0
(-2975 650);
PAINT ORANGE (-2975 650);
DISPLAY INVISIBLE (-2975 650);
FORCEPROP 1 LAST BODY_TYPE PLUMBING
J 0
(-3020 607);
DISPLAY 0.340426 (-3020 607);
PAINT GREEN (-3020 607);
DISPLAY INVISIBLE (-3020 607);
FORCEPROP 1 LAST PATH I1
J 0
(-2900 650);
DISPLAY 0.872340 (-2900 650);
PAINT AQUA (-2900 650);
DISPLAY INVISIBLE (-2900 650);
FORCEPROP 2 LAST ROOM DDR4_CH_A
J 0
(-2975 655);
PAINT ORANGE (-2975 655);
DISPLAY INVISIBLE (-2975 655);
FORCEPROP 1 LAST HDL_POWER GND
J 0
(-2975 800);
DISPLAY 1.404255 (-2975 800);
PAINT GREEN (-2975 800);
DISPLAY INVISIBLE (-2975 800);
FORCEADD OFFPAGE..1
(-2375 3100);
FORCEPROP 2 LAST $XR0 24 
J 0
(-2596 3100);
DISPLAY 0.638298 (-2596 3100);
PAINT MONO (-2596 3100);
FORCEPROP 2 LAST $XR1 45 
J 0
(-2686 3100);
DISPLAY 0.638298 (-2686 3100);
PAINT MONO (-2686 3100);
FORCEPROP 2 LAST CDS_LIB mstr_standard
J 0
(-2375 3100);
DISPLAY 0.787234 (-2375 3100);
PAINT MONO (-2375 3100);
DISPLAY INVISIBLE (-2375 3100);
FORCEPROP 1 LAST OFFPAGE TRUE
J 0
(-2050 2975);
DISPLAY 0.936170 (-2050 2975);
PAINT GREEN (-2050 2975);
DISPLAY INVISIBLE (-2050 2975);
FORCEPROP 1 LAST COMMENT_BODY TRUE
J 0
(-2250 3000);
DISPLAY 0.936170 (-2250 3000);
PAINT GREEN (-2250 3000);
DISPLAY INVISIBLE (-2250 3000);
FORCEPROP 2 LAST PATH I10
J 0
(-2575 3150);
DISPLAY 1.021277 (-2575 3150);
PAINT ORANGE (-2575 3150);
DISPLAY INVISIBLE (-2575 3150);
FORCEADD TAP..6
R 2
(-75 3250);
FORCEPROP 3 LASTPIN (-125 3250) SIG_NAME M_B_DQ<43>
J 0
(-115 3260);
DISPLAY 0.659574 (-115 3260);
PAINT MONO (-115 3260);
DISPLAY INVISIBLE (-115 3260);
FORCEPROP 1 LASTPIN (-125 3250) BN 43
J 2
(-75 3260);
DISPLAY 0.617021 (-75 3260);
PAINT PINK (-75 3260);
FORCEPROP 2 LAST CDS_LIB mstr_standard
J 2
(-75 3250);
DISPLAY 0.787234 (-75 3250);
PAINT MONO (-75 3250);
DISPLAY INVISIBLE (-75 3250);
FORCEPROP 1 LAST BODY_TYPE PLUMBING
J 2
(-75 3200);
DISPLAY 1.234043 (-75 3200);
PAINT GREEN (-75 3200);
DISPLAY INVISIBLE (-75 3200);
FORCEPROP 1 LAST HDL_TAP TRUE
J 2
(-400 3125);
DISPLAY 1.234043 (-400 3125);
PAINT GREEN (-400 3125);
DISPLAY INVISIBLE (-400 3125);
FORCEPROP 1 LAST PATH I100
J 2
(-73 3250);
DISPLAY 0.872340 (-73 3250);
PAINT GREEN (-73 3250);
DISPLAY INVISIBLE (-73 3250);
FORCEADD TAP..6
R 2
(-75 3350);
FORCEPROP 3 LASTPIN (-125 3350) SIG_NAME M_B_DQ<45>
J 0
(-115 3360);
DISPLAY 0.659574 (-115 3360);
PAINT MONO (-115 3360);
DISPLAY INVISIBLE (-115 3360);
FORCEPROP 1 LASTPIN (-125 3350) BN 45
J 2
(-75 3360);
DISPLAY 0.617021 (-75 3360);
PAINT PINK (-75 3360);
FORCEPROP 2 LAST CDS_LIB mstr_standard
J 2
(-75 3350);
DISPLAY 0.787234 (-75 3350);
PAINT MONO (-75 3350);
DISPLAY INVISIBLE (-75 3350);
FORCEPROP 1 LAST BODY_TYPE PLUMBING
J 2
(-75 3300);
DISPLAY 1.234043 (-75 3300);
PAINT GREEN (-75 3300);
DISPLAY INVISIBLE (-75 3300);
FORCEPROP 1 LAST HDL_TAP TRUE
J 2
(-400 3225);
DISPLAY 1.234043 (-400 3225);
PAINT GREEN (-400 3225);
DISPLAY INVISIBLE (-400 3225);
FORCEPROP 1 LAST PATH I101
J 2
(-73 3350);
DISPLAY 0.872340 (-73 3350);
PAINT GREEN (-73 3350);
DISPLAY INVISIBLE (-73 3350);
FORCEADD TAP..6
R 2
(-75 3450);
FORCEPROP 3 LASTPIN (-125 3450) SIG_NAME M_B_DQ<47>
J 0
(-115 3460);
DISPLAY 0.659574 (-115 3460);
PAINT MONO (-115 3460);
DISPLAY INVISIBLE (-115 3460);
FORCEPROP 1 LASTPIN (-125 3450) BN 47
J 2
(-75 3460);
DISPLAY 0.617021 (-75 3460);
PAINT PINK (-75 3460);
FORCEPROP 2 LAST CDS_LIB mstr_standard
J 2
(-75 3450);
DISPLAY 0.787234 (-75 3450);
PAINT MONO (-75 3450);
DISPLAY INVISIBLE (-75 3450);
FORCEPROP 1 LAST BODY_TYPE PLUMBING
J 2
(-75 3400);
DISPLAY 1.234043 (-75 3400);
PAINT GREEN (-75 3400);
DISPLAY INVISIBLE (-75 3400);
FORCEPROP 1 LAST HDL_TAP TRUE
J 2
(-400 3325);
DISPLAY 1.234043 (-400 3325);
PAINT GREEN (-400 3325);
DISPLAY INVISIBLE (-400 3325);
FORCEPROP 1 LAST PATH I102
J 2
(-73 3450);
DISPLAY 0.872340 (-73 3450);
PAINT GREEN (-73 3450);
DISPLAY INVISIBLE (-73 3450);
FORCEADD TAP..6
R 2
(-75 3400);
FORCEPROP 3 LASTPIN (-125 3400) SIG_NAME M_B_DQ<46>
J 0
(-115 3410);
DISPLAY 0.659574 (-115 3410);
PAINT MONO (-115 3410);
DISPLAY INVISIBLE (-115 3410);
FORCEPROP 1 LASTPIN (-125 3400) BN 46
J 2
(-75 3410);
DISPLAY 0.617021 (-75 3410);
PAINT PINK (-75 3410);
FORCEPROP 2 LAST CDS_LIB mstr_standard
J 2
(-75 3400);
DISPLAY 0.787234 (-75 3400);
PAINT MONO (-75 3400);
DISPLAY INVISIBLE (-75 3400);
FORCEPROP 1 LAST BODY_TYPE PLUMBING
J 2
(-75 3350);
DISPLAY 1.234043 (-75 3350);
PAINT GREEN (-75 3350);
DISPLAY INVISIBLE (-75 3350);
FORCEPROP 1 LAST HDL_TAP TRUE
J 2
(-400 3275);
DISPLAY 1.234043 (-400 3275);
PAINT GREEN (-400 3275);
DISPLAY INVISIBLE (-400 3275);
FORCEPROP 1 LAST PATH I103
J 2
(-73 3400);
DISPLAY 0.872340 (-73 3400);
PAINT GREEN (-73 3400);
DISPLAY INVISIBLE (-73 3400);
FORCEADD TAP..6
R 2
(-75 3550);
FORCEPROP 3 LASTPIN (-125 3550) SIG_NAME M_B_DQ<49>
J 0
(-115 3560);
DISPLAY 0.659574 (-115 3560);
PAINT MONO (-115 3560);
DISPLAY INVISIBLE (-115 3560);
FORCEPROP 1 LASTPIN (-125 3550) BN 49
J 2
(-75 3560);
DISPLAY 0.617021 (-75 3560);
PAINT PINK (-75 3560);
FORCEPROP 2 LAST CDS_LIB mstr_standard
J 2
(-75 3550);
DISPLAY 0.787234 (-75 3550);
PAINT MONO (-75 3550);
DISPLAY INVISIBLE (-75 3550);
FORCEPROP 1 LAST BODY_TYPE PLUMBING
J 2
(-75 3500);
DISPLAY 1.234043 (-75 3500);
PAINT GREEN (-75 3500);
DISPLAY INVISIBLE (-75 3500);
FORCEPROP 1 LAST HDL_TAP TRUE
J 2
(-400 3425);
DISPLAY 1.234043 (-400 3425);
PAINT GREEN (-400 3425);
DISPLAY INVISIBLE (-400 3425);
FORCEPROP 1 LAST PATH I104
J 2
(-73 3550);
DISPLAY 0.872340 (-73 3550);
PAINT GREEN (-73 3550);
DISPLAY INVISIBLE (-73 3550);
FORCEADD TAP..6
R 2
(-75 3500);
FORCEPROP 3 LASTPIN (-125 3500) SIG_NAME M_B_DQ<48>
J 0
(-115 3510);
DISPLAY 0.659574 (-115 3510);
PAINT MONO (-115 3510);
DISPLAY INVISIBLE (-115 3510);
FORCEPROP 1 LASTPIN (-125 3500) BN 48
J 2
(-75 3510);
DISPLAY 0.617021 (-75 3510);
PAINT PINK (-75 3510);
FORCEPROP 2 LAST CDS_LIB mstr_standard
J 2
(-75 3500);
DISPLAY 0.787234 (-75 3500);
PAINT MONO (-75 3500);
DISPLAY INVISIBLE (-75 3500);
FORCEPROP 1 LAST BODY_TYPE PLUMBING
J 2
(-75 3450);
DISPLAY 1.234043 (-75 3450);
PAINT GREEN (-75 3450);
DISPLAY INVISIBLE (-75 3450);
FORCEPROP 1 LAST HDL_TAP TRUE
J 2
(-400 3375);
DISPLAY 1.234043 (-400 3375);
PAINT GREEN (-400 3375);
DISPLAY INVISIBLE (-400 3375);
FORCEPROP 1 LAST PATH I105
J 2
(-73 3500);
DISPLAY 0.872340 (-73 3500);
PAINT GREEN (-73 3500);
DISPLAY INVISIBLE (-73 3500);
FORCEADD TAP..6
R 2
(-75 3600);
FORCEPROP 3 LASTPIN (-125 3600) SIG_NAME M_B_DQ<50>
J 0
(-115 3610);
DISPLAY 0.659574 (-115 3610);
PAINT MONO (-115 3610);
DISPLAY INVISIBLE (-115 3610);
FORCEPROP 1 LASTPIN (-125 3600) BN 50
J 2
(-75 3610);
DISPLAY 0.617021 (-75 3610);
PAINT PINK (-75 3610);
FORCEPROP 2 LAST CDS_LIB mstr_standard
J 2
(-75 3600);
DISPLAY 0.787234 (-75 3600);
PAINT MONO (-75 3600);
DISPLAY INVISIBLE (-75 3600);
FORCEPROP 1 LAST BODY_TYPE PLUMBING
J 2
(-75 3550);
DISPLAY 1.234043 (-75 3550);
PAINT GREEN (-75 3550);
DISPLAY INVISIBLE (-75 3550);
FORCEPROP 1 LAST HDL_TAP TRUE
J 2
(-400 3475);
DISPLAY 1.234043 (-400 3475);
PAINT GREEN (-400 3475);
DISPLAY INVISIBLE (-400 3475);
FORCEPROP 1 LAST PATH I106
J 2
(-73 3600);
DISPLAY 0.872340 (-73 3600);
PAINT GREEN (-73 3600);
DISPLAY INVISIBLE (-73 3600);
FORCEADD TAP..6
R 2
(-75 3650);
FORCEPROP 3 LASTPIN (-125 3650) SIG_NAME M_B_DQ<51>
J 0
(-115 3660);
DISPLAY 0.659574 (-115 3660);
PAINT MONO (-115 3660);
DISPLAY INVISIBLE (-115 3660);
FORCEPROP 1 LASTPIN (-125 3650) BN 51
J 2
(-75 3660);
DISPLAY 0.617021 (-75 3660);
PAINT PINK (-75 3660);
FORCEPROP 2 LAST CDS_LIB mstr_standard
J 2
(-75 3650);
DISPLAY 0.787234 (-75 3650);
PAINT MONO (-75 3650);
DISPLAY INVISIBLE (-75 3650);
FORCEPROP 1 LAST BODY_TYPE PLUMBING
J 2
(-75 3600);
DISPLAY 1.234043 (-75 3600);
PAINT GREEN (-75 3600);
DISPLAY INVISIBLE (-75 3600);
FORCEPROP 1 LAST HDL_TAP TRUE
J 2
(-400 3525);
DISPLAY 1.234043 (-400 3525);
PAINT GREEN (-400 3525);
DISPLAY INVISIBLE (-400 3525);
FORCEPROP 1 LAST PATH I107
J 2
(-73 3650);
DISPLAY 0.872340 (-73 3650);
PAINT GREEN (-73 3650);
DISPLAY INVISIBLE (-73 3650);
FORCEADD TAP..6
R 2
(-75 3700);
FORCEPROP 3 LASTPIN (-125 3700) SIG_NAME M_B_DQ<52>
J 0
(-115 3710);
DISPLAY 0.659574 (-115 3710);
PAINT MONO (-115 3710);
DISPLAY INVISIBLE (-115 3710);
FORCEPROP 1 LASTPIN (-125 3700) BN 52
J 2
(-75 3710);
DISPLAY 0.617021 (-75 3710);
PAINT PINK (-75 3710);
FORCEPROP 2 LAST CDS_LIB mstr_standard
J 2
(-75 3700);
DISPLAY 0.787234 (-75 3700);
PAINT MONO (-75 3700);
DISPLAY INVISIBLE (-75 3700);
FORCEPROP 1 LAST BODY_TYPE PLUMBING
J 2
(-75 3650);
DISPLAY 1.234043 (-75 3650);
PAINT GREEN (-75 3650);
DISPLAY INVISIBLE (-75 3650);
FORCEPROP 1 LAST HDL_TAP TRUE
J 2
(-400 3575);
DISPLAY 1.234043 (-400 3575);
PAINT GREEN (-400 3575);
DISPLAY INVISIBLE (-400 3575);
FORCEPROP 1 LAST PATH I108
J 2
(-73 3700);
DISPLAY 0.872340 (-73 3700);
PAINT GREEN (-73 3700);
DISPLAY INVISIBLE (-73 3700);
FORCEADD PVDDQ_ABC..1
(600 2200);
FORCEPROP 3 LASTPIN (600 2150) SIG_NAME PVDDQ_ABC\g
J 0
(610 2160);
DISPLAY 0.659574 (610 2160);
PAINT MONO (610 2160);
DISPLAY INVISIBLE (610 2160);
FORCEPROP 1 LAST VOLTAGE 1.2V
J 0
(555 2157);
DISPLAY 0.340426 (555 2157);
PAINT SKYBLUE (555 2157);
DISPLAY INVISIBLE (555 2157);
FORCEPROP 2 LAST BOM_COST MEM
J 0
(600 2205);
PAINT ORANGE (600 2205);
DISPLAY INVISIBLE (600 2205);
FORCEPROP 2 LAST CDS_LIB mstr_symbols
J 0
(600 2200);
PAINT ORANGE (600 2200);
DISPLAY INVISIBLE (600 2200);
FORCEPROP 1 LAST BODY_TYPE PLUMBING
J 0
(555 2157);
DISPLAY 0.340426 (555 2157);
PAINT GREEN (555 2157);
DISPLAY INVISIBLE (555 2157);
FORCEPROP 1 LAST PATH I109
J 0
(650 2225);
DISPLAY 0.872340 (650 2225);
PAINT AQUA (650 2225);
DISPLAY INVISIBLE (650 2225);
FORCEPROP 2 LAST ROOM DDR4_CH_A
J 0
(600 2300);
DISPLAY 0.787234 (600 2300);
PAINT ORANGE (600 2300);
DISPLAY INVISIBLE (600 2300);
FORCEPROP 1 LAST HDL_POWER PVDDQ_ABC
J 1
(600 2250);
DISPLAY 0.872340 (600 2250);
PAINT GREEN (600 2250);
DISPLAY INVISIBLE (600 2250);
FORCEADD OFFPAGE..1
(-2225 800);
FORCEPROP 2 LAST $XR0 89 
J 0
(-2476 800);
DISPLAY 0.638298 (-2476 800);
PAINT MONO (-2476 800);
FORCEPROP 2 LAST $XR1 43 
J 0
(-2566 800);
DISPLAY 0.638298 (-2566 800);
PAINT MONO (-2566 800);
FORCEPROP 2 LAST $XR2 44 
J 0
(-2656 800);
DISPLAY 0.638298 (-2656 800);
PAINT MONO (-2656 800);
FORCEPROP 2 LAST $XR3 45 
J 0
(-2746 800);
DISPLAY 0.638298 (-2746 800);
PAINT MONO (-2746 800);
FORCEPROP 2 LAST $XR4 47 
J 0
(-2836 800);
DISPLAY 0.638298 (-2836 800);
PAINT MONO (-2836 800);
FORCEPROP 2 LAST $XR5 48 
J 0
(-2926 800);
DISPLAY 0.638298 (-2926 800);
PAINT MONO (-2926 800);
FORCEPROP 2 LAST CDS_LIB mstr_standard
J 0
(-2225 800);
PAINT ORANGE (-2225 800);
DISPLAY INVISIBLE (-2225 800);
FORCEPROP 1 LAST OFFPAGE TRUE
J 0
(-1900 675);
DISPLAY 0.936170 (-1900 675);
PAINT GREEN (-1900 675);
DISPLAY INVISIBLE (-1900 675);
FORCEPROP 1 LAST COMMENT_BODY TRUE
J 0
(-2100 700);
DISPLAY 0.936170 (-2100 700);
PAINT GREEN (-2100 700);
DISPLAY INVISIBLE (-2100 700);
FORCEPROP 2 LAST PATH I11
J 0
(-2475 850);
DISPLAY 1.021277 (-2475 850);
PAINT ORANGE (-2475 850);
DISPLAY INVISIBLE (-2475 850);
FORCEADD PVTT_ABC..1
(825 2350);
FORCEPROP 3 LASTPIN (825 2300) SIG_NAME PVTT_ABC\g
J 0
(835 2310);
DISPLAY 0.659574 (835 2310);
PAINT MONO (835 2310);
DISPLAY INVISIBLE (835 2310);
FORCEPROP 1 LAST VOLTAGE 0.6V
J 0
(780 2307);
DISPLAY 0.340426 (780 2307);
PAINT SKYBLUE (780 2307);
DISPLAY INVISIBLE (780 2307);
FORCEPROP 2 LAST BOM_COST MEM
J 0
(825 2355);
PAINT ORANGE (825 2355);
DISPLAY INVISIBLE (825 2355);
FORCEPROP 2 LAST CDS_LIB mstr_symbols
J 0
(825 2350);
PAINT ORANGE (825 2350);
DISPLAY INVISIBLE (825 2350);
FORCEPROP 1 LAST BODY_TYPE PLUMBING
J 0
(780 2307);
DISPLAY 0.340426 (780 2307);
PAINT GREEN (780 2307);
DISPLAY INVISIBLE (780 2307);
FORCEPROP 1 LAST PATH I110
J 0
(875 2375);
DISPLAY 0.872340 (875 2375);
PAINT AQUA (875 2375);
DISPLAY INVISIBLE (875 2375);
FORCEPROP 2 LAST ROOM DDR4_CH_A
J 0
(825 2450);
DISPLAY 0.787234 (825 2450);
PAINT ORANGE (825 2450);
DISPLAY INVISIBLE (825 2450);
FORCEPROP 1 LAST HDL_POWER PVTT_ABC
J 1
(825 2400);
DISPLAY 0.872340 (825 2400);
PAINT GREEN (825 2400);
DISPLAY INVISIBLE (825 2400);
FORCEADD PVPP_ABC..1
(975 2650);
FORCEPROP 3 LASTPIN (975 2600) SIG_NAME PVPP_ABC\g
J 0
(985 2610);
DISPLAY 0.659574 (985 2610);
PAINT MONO (985 2610);
DISPLAY INVISIBLE (985 2610);
FORCEPROP 1 LAST VOLTAGE 2.5V
J 0
(930 2607);
DISPLAY 0.340426 (930 2607);
PAINT SKYBLUE (930 2607);
DISPLAY INVISIBLE (930 2607);
FORCEPROP 0 LAST BOM_COST MEM
J 0
(975 2750);
PAINT ORANGE (975 2750);
DISPLAY INVISIBLE (975 2750);
FORCEPROP 2 LAST CDS_LIB mstr_symbols
J 0
(975 2650);
PAINT ORANGE (975 2650);
DISPLAY INVISIBLE (975 2650);
FORCEPROP 1 LAST BODY_TYPE PLUMBING
J 0
(930 2607);
DISPLAY 0.340426 (930 2607);
PAINT GREEN (930 2607);
DISPLAY INVISIBLE (930 2607);
FORCEPROP 1 LAST PATH I111
J 0
(1025 2675);
DISPLAY 0.872340 (1025 2675);
PAINT AQUA (1025 2675);
DISPLAY INVISIBLE (1025 2675);
FORCEPROP 2 LAST ROOM DDR4_CH_A
J 0
(975 2750);
PAINT ORANGE (975 2750);
DISPLAY INVISIBLE (975 2750);
FORCEPROP 1 LAST HDL_POWER PVPP_ABC
J 1
(975 2700);
DISPLAY 0.872340 (975 2700);
PAINT GREEN (975 2700);
DISPLAY INVISIBLE (975 2700);
FORCEADD SCONN288_H44441003..2
(1625 3950);
FORCEPROP 1 LAST LOCATION J6U1
J 0
(1225 5050);
DISPLAY 0.617021 (1225 5050);
PAINT AQUA (1225 5050);
FORCEPROP 1 LAST PART_NUMBER H44441-003
J 0
(1225 2850);
DISPLAY 0.617021 (1225 2850);
PAINT BLUE (1225 2850);
FORCEPROP 1 LAST MATERIAL SCONN
J 0
(1225 5000);
DISPLAY 0.617021 (1225 5000);
PAINT SKYBLUE (1225 5000);
FORCEPROP 2 LASTPIN (2075 4800) $PN 51
J 0
(2085 4810);
DISPLAY 0.617021 (2085 4810);
PAINT ORANGE (2085 4810);
FORCEPROP 2 LASTPIN (2075 4750) $PN 52
J 0
(2085 4760);
DISPLAY 0.617021 (2085 4760);
PAINT ORANGE (2085 4760);
FORCEPROP 2 LASTPIN (2075 4700) $PN 132
J 0
(2085 4710);
DISPLAY 0.617021 (2085 4710);
PAINT ORANGE (2085 4710);
FORCEPROP 2 LASTPIN (2075 4650) $PN 133
J 0
(2085 4660);
DISPLAY 0.617021 (2085 4660);
PAINT ORANGE (2085 4660);
FORCEPROP 2 LASTPIN (2075 4600) $PN 121
J 0
(2085 4610);
DISPLAY 0.617021 (2085 4610);
PAINT ORANGE (2085 4610);
FORCEPROP 2 LASTPIN (2075 4550) $PN 122
J 0
(2085 4560);
DISPLAY 0.617021 (2085 4560);
PAINT ORANGE (2085 4560);
FORCEPROP 2 LASTPIN (2075 4500) $PN 110
J 0
(2085 4510);
DISPLAY 0.617021 (2085 4510);
PAINT ORANGE (2085 4510);
FORCEPROP 2 LASTPIN (2075 4450) $PN 111
J 0
(2085 4460);
DISPLAY 0.617021 (2085 4460);
PAINT ORANGE (2085 4460);
FORCEPROP 2 LASTPIN (2075 4400) $PN 99
J 0
(2085 4410);
DISPLAY 0.617021 (2085 4410);
PAINT ORANGE (2085 4410);
FORCEPROP 2 LASTPIN (2075 4350) $PN 100
J 0
(2085 4360);
DISPLAY 0.617021 (2085 4360);
PAINT ORANGE (2085 4360);
FORCEPROP 2 LASTPIN (2075 4300) $PN 40
J 0
(2085 4310);
DISPLAY 0.617021 (2085 4310);
PAINT ORANGE (2085 4310);
FORCEPROP 2 LASTPIN (2075 4250) $PN 41
J 0
(2085 4260);
DISPLAY 0.617021 (2085 4260);
PAINT ORANGE (2085 4260);
FORCEPROP 2 LASTPIN (2075 4200) $PN 29
J 0
(2085 4210);
DISPLAY 0.617021 (2085 4210);
PAINT ORANGE (2085 4210);
FORCEPROP 2 LASTPIN (2075 4150) $PN 30
J 0
(2085 4160);
DISPLAY 0.617021 (2085 4160);
PAINT ORANGE (2085 4160);
FORCEPROP 2 LASTPIN (2075 4100) $PN 18
J 0
(2085 4110);
DISPLAY 0.617021 (2085 4110);
PAINT ORANGE (2085 4110);
FORCEPROP 2 LASTPIN (2075 4050) $PN 19
J 0
(2085 4060);
DISPLAY 0.617021 (2085 4060);
PAINT ORANGE (2085 4060);
FORCEPROP 2 LASTPIN (2075 4000) $PN 7
J 0
(2085 4010);
DISPLAY 0.617021 (2085 4010);
PAINT ORANGE (2085 4010);
FORCEPROP 2 LASTPIN (2075 3950) $PN 8
J 0
(2085 3960);
DISPLAY 0.617021 (2085 3960);
PAINT ORANGE (2085 3960);
FORCEPROP 2 LASTPIN (2075 3900) $PN 197
J 0
(2085 3910);
DISPLAY 0.617021 (2085 3910);
PAINT ORANGE (2085 3910);
FORCEPROP 2 LASTPIN (2075 3850) $PN 196
J 0
(2085 3860);
DISPLAY 0.617021 (2085 3860);
PAINT ORANGE (2085 3860);
FORCEPROP 2 LASTPIN (2075 3800) $PN 278
J 0
(2085 3810);
DISPLAY 0.617021 (2085 3810);
PAINT ORANGE (2085 3810);
FORCEPROP 2 LASTPIN (2075 3750) $PN 277
J 0
(2085 3760);
DISPLAY 0.617021 (2085 3760);
PAINT ORANGE (2085 3760);
FORCEPROP 2 LASTPIN (2075 3700) $PN 267
J 0
(2085 3710);
DISPLAY 0.617021 (2085 3710);
PAINT ORANGE (2085 3710);
FORCEPROP 2 LASTPIN (2075 3650) $PN 266
J 0
(2085 3660);
DISPLAY 0.617021 (2085 3660);
PAINT ORANGE (2085 3660);
FORCEPROP 2 LASTPIN (2075 3600) $PN 256
J 0
(2085 3610);
DISPLAY 0.617021 (2085 3610);
PAINT ORANGE (2085 3610);
FORCEPROP 2 LASTPIN (2075 3550) $PN 255
J 0
(2085 3560);
DISPLAY 0.617021 (2085 3560);
PAINT ORANGE (2085 3560);
FORCEPROP 2 LASTPIN (2075 3500) $PN 245
J 0
(2085 3510);
DISPLAY 0.617021 (2085 3510);
PAINT ORANGE (2085 3510);
FORCEPROP 2 LASTPIN (2075 3450) $PN 244
J 0
(2085 3460);
DISPLAY 0.617021 (2085 3460);
PAINT ORANGE (2085 3460);
FORCEPROP 2 LASTPIN (2075 3400) $PN 186
J 0
(2085 3410);
DISPLAY 0.617021 (2085 3410);
PAINT ORANGE (2085 3410);
FORCEPROP 2 LASTPIN (2075 3350) $PN 185
J 0
(2085 3360);
DISPLAY 0.617021 (2085 3360);
PAINT ORANGE (2085 3360);
FORCEPROP 2 LASTPIN (2075 3300) $PN 175
J 0
(2085 3310);
DISPLAY 0.617021 (2085 3310);
PAINT ORANGE (2085 3310);
FORCEPROP 2 LASTPIN (2075 3250) $PN 174
J 0
(2085 3260);
DISPLAY 0.617021 (2085 3260);
PAINT ORANGE (2085 3260);
FORCEPROP 2 LASTPIN (2075 3200) $PN 164
J 0
(2085 3210);
DISPLAY 0.617021 (2085 3210);
PAINT ORANGE (2085 3210);
FORCEPROP 2 LASTPIN (2075 3150) $PN 163
J 0
(2085 3160);
DISPLAY 0.617021 (2085 3160);
PAINT ORANGE (2085 3160);
FORCEPROP 2 LASTPIN (2075 3100) $PN 153
J 0
(2085 3110);
DISPLAY 0.617021 (2085 3110);
PAINT ORANGE (2085 3110);
FORCEPROP 2 LASTPIN (2075 3050) $PN 152
J 0
(2085 3060);
DISPLAY 0.617021 (2085 3060);
PAINT ORANGE (2085 3060);
FORCEPROP 1 LAST PACK_TYPE PIP
J 0
(1225 5100);
PAINT SKYBLUE (1225 5100);
DISPLAY INVISIBLE (1225 5100);
FORCEPROP 2 LAST BOM_COST MEM
J 0
(1625 3950);
PAINT ORANGE (1625 3950);
DISPLAY INVISIBLE (1625 3950);
FORCEPROP 2 LAST CDS_LIB mstr_sconn
J 0
(1625 3950);
PAINT ORANGE (1625 3950);
DISPLAY INVISIBLE (1625 3950);
FORCEPROP 2 LAST SEC_TYPE PIP
J 0
(1225 5100);
DISPLAY 1.021277 (1225 5100);
PAINT ORANGE (1225 5100);
DISPLAY INVISIBLE (1225 5100);
FORCEPROP 2 LAST SEC 2
J 0
(1225 5100);
DISPLAY 0.680851 (1225 5100);
PAINT MONO (1225 5100);
DISPLAY INVISIBLE (1225 5100);
FORCEPROP 2 LAST CDS_LOCATION J6U1
J 0
(1225 5050);
DISPLAY 0.617021 (1225 5050);
PAINT AQUA (1225 5050);
DISPLAY INVISIBLE (1225 5050);
FORCEPROP 1 LAST PATH I112
J 0
(1625 5000);
PAINT GREEN (1625 5000);
DISPLAY INVISIBLE (1625 5000);
FORCEPROP 2 LAST ROOM DDR4_CH_B
J 0
(1225 5150);
PAINT ORANGE (1225 5150);
DISPLAY INVISIBLE (1225 5150);
FORCEADD OFFPAGE..1
(-2225 4300);
FORCEPROP 2 LAST $XR0 24 
J 0
(-2476 4300);
DISPLAY 0.638298 (-2476 4300);
PAINT MONO (-2476 4300);
FORCEPROP 2 LAST $XR1 45 
J 0
(-2566 4300);
DISPLAY 0.638298 (-2566 4300);
PAINT MONO (-2566 4300);
FORCEPROP 2 LAST CDS_LIB mstr_standard
J 0
(-2225 4300);
DISPLAY 0.787234 (-2225 4300);
PAINT MONO (-2225 4300);
DISPLAY INVISIBLE (-2225 4300);
FORCEPROP 1 LAST OFFPAGE TRUE
J 0
(-1900 4175);
DISPLAY 0.936170 (-1900 4175);
PAINT GREEN (-1900 4175);
DISPLAY INVISIBLE (-1900 4175);
FORCEPROP 1 LAST COMMENT_BODY TRUE
J 0
(-2100 4200);
DISPLAY 0.936170 (-2100 4200);
PAINT GREEN (-2100 4200);
DISPLAY INVISIBLE (-2100 4200);
FORCEPROP 2 LAST PATH I113
J 0
(-2425 4350);
DISPLAY 1.021277 (-2425 4350);
PAINT ORANGE (-2425 4350);
DISPLAY INVISIBLE (-2425 4350);
FORCEADD TAP..6
(-1575 3750);
FORCEPROP 3 LASTPIN (-1525 3750) SIG_NAME M_B_MA<7>
J 0
(-1515 3760);
DISPLAY 0.659574 (-1515 3760);
PAINT MONO (-1515 3760);
DISPLAY INVISIBLE (-1515 3760);
FORCEPROP 1 LASTPIN (-1525 3750) BN 7
J 0
(-1575 3760);
DISPLAY 0.617021 (-1575 3760);
PAINT PINK (-1575 3760);
FORCEPROP 2 LAST CDS_LIB mstr_standard
J 2
(-1575 3750);
DISPLAY 0.787234 (-1575 3750);
PAINT MONO (-1575 3750);
DISPLAY INVISIBLE (-1575 3750);
FORCEPROP 1 LAST BODY_TYPE PLUMBING
J 0
(-1575 3700);
DISPLAY 1.234043 (-1575 3700);
PAINT GREEN (-1575 3700);
DISPLAY INVISIBLE (-1575 3700);
FORCEPROP 1 LAST HDL_TAP TRUE
J 0
(-1250 3625);
DISPLAY 1.234043 (-1250 3625);
PAINT GREEN (-1250 3625);
DISPLAY INVISIBLE (-1250 3625);
FORCEPROP 1 LAST PATH I114
J 0
(-1577 3750);
DISPLAY 0.872340 (-1577 3750);
PAINT GREEN (-1577 3750);
DISPLAY INVISIBLE (-1577 3750);
FORCEADD TAP..6
(-1575 3800);
FORCEPROP 3 LASTPIN (-1525 3800) SIG_NAME M_B_MA<8>
J 0
(-1515 3810);
DISPLAY 0.659574 (-1515 3810);
PAINT MONO (-1515 3810);
DISPLAY INVISIBLE (-1515 3810);
FORCEPROP 1 LASTPIN (-1525 3800) BN 8
J 0
(-1575 3810);
DISPLAY 0.617021 (-1575 3810);
PAINT PINK (-1575 3810);
FORCEPROP 2 LAST CDS_LIB mstr_standard
J 2
(-1575 3800);
DISPLAY 0.787234 (-1575 3800);
PAINT MONO (-1575 3800);
DISPLAY INVISIBLE (-1575 3800);
FORCEPROP 1 LAST BODY_TYPE PLUMBING
J 0
(-1575 3750);
DISPLAY 1.234043 (-1575 3750);
PAINT GREEN (-1575 3750);
DISPLAY INVISIBLE (-1575 3750);
FORCEPROP 1 LAST HDL_TAP TRUE
J 0
(-1250 3675);
DISPLAY 1.234043 (-1250 3675);
PAINT GREEN (-1250 3675);
DISPLAY INVISIBLE (-1250 3675);
FORCEPROP 1 LAST PATH I115
J 0
(-1577 3800);
DISPLAY 0.872340 (-1577 3800);
PAINT GREEN (-1577 3800);
DISPLAY INVISIBLE (-1577 3800);
FORCEADD TAP..6
(-1575 3950);
FORCEPROP 3 LASTPIN (-1525 3950) SIG_NAME M_B_MA<11>
J 0
(-1515 3960);
DISPLAY 0.659574 (-1515 3960);
PAINT MONO (-1515 3960);
DISPLAY INVISIBLE (-1515 3960);
FORCEPROP 1 LASTPIN (-1525 3950) BN 11
J 0
(-1575 3960);
DISPLAY 0.617021 (-1575 3960);
PAINT PINK (-1575 3960);
FORCEPROP 2 LAST CDS_LIB mstr_standard
J 2
(-1575 3950);
DISPLAY 0.787234 (-1575 3950);
PAINT MONO (-1575 3950);
DISPLAY INVISIBLE (-1575 3950);
FORCEPROP 1 LAST BODY_TYPE PLUMBING
J 0
(-1575 3900);
DISPLAY 1.234043 (-1575 3900);
PAINT GREEN (-1575 3900);
DISPLAY INVISIBLE (-1575 3900);
FORCEPROP 1 LAST HDL_TAP TRUE
J 0
(-1250 3825);
DISPLAY 1.234043 (-1250 3825);
PAINT GREEN (-1250 3825);
DISPLAY INVISIBLE (-1250 3825);
FORCEPROP 1 LAST PATH I116
J 0
(-1577 3950);
DISPLAY 0.872340 (-1577 3950);
PAINT GREEN (-1577 3950);
DISPLAY INVISIBLE (-1577 3950);
FORCEADD TAP..6
(-1575 3900);
FORCEPROP 3 LASTPIN (-1525 3900) SIG_NAME M_B_MA<10>
J 0
(-1515 3910);
DISPLAY 0.659574 (-1515 3910);
PAINT MONO (-1515 3910);
DISPLAY INVISIBLE (-1515 3910);
FORCEPROP 1 LASTPIN (-1525 3900) BN 10
J 0
(-1575 3910);
DISPLAY 0.617021 (-1575 3910);
PAINT PINK (-1575 3910);
FORCEPROP 2 LAST CDS_LIB mstr_standard
J 2
(-1575 3900);
DISPLAY 0.787234 (-1575 3900);
PAINT MONO (-1575 3900);
DISPLAY INVISIBLE (-1575 3900);
FORCEPROP 1 LAST BODY_TYPE PLUMBING
J 0
(-1575 3850);
DISPLAY 1.234043 (-1575 3850);
PAINT GREEN (-1575 3850);
DISPLAY INVISIBLE (-1575 3850);
FORCEPROP 1 LAST HDL_TAP TRUE
J 0
(-1250 3775);
DISPLAY 1.234043 (-1250 3775);
PAINT GREEN (-1250 3775);
DISPLAY INVISIBLE (-1250 3775);
FORCEPROP 1 LAST PATH I117
J 0
(-1577 3900);
DISPLAY 0.872340 (-1577 3900);
PAINT GREEN (-1577 3900);
DISPLAY INVISIBLE (-1577 3900);
FORCEADD TAP..6
(-1575 3850);
FORCEPROP 3 LASTPIN (-1525 3850) SIG_NAME M_B_MA<9>
J 0
(-1515 3860);
DISPLAY 0.659574 (-1515 3860);
PAINT MONO (-1515 3860);
DISPLAY INVISIBLE (-1515 3860);
FORCEPROP 1 LASTPIN (-1525 3850) BN 9
J 0
(-1575 3860);
DISPLAY 0.617021 (-1575 3860);
PAINT PINK (-1575 3860);
FORCEPROP 2 LAST CDS_LIB mstr_standard
J 2
(-1575 3850);
DISPLAY 0.787234 (-1575 3850);
PAINT MONO (-1575 3850);
DISPLAY INVISIBLE (-1575 3850);
FORCEPROP 1 LAST BODY_TYPE PLUMBING
J 0
(-1575 3800);
DISPLAY 1.234043 (-1575 3800);
PAINT GREEN (-1575 3800);
DISPLAY INVISIBLE (-1575 3800);
FORCEPROP 1 LAST HDL_TAP TRUE
J 0
(-1250 3725);
DISPLAY 1.234043 (-1250 3725);
PAINT GREEN (-1250 3725);
DISPLAY INVISIBLE (-1250 3725);
FORCEPROP 1 LAST PATH I118
J 0
(-1577 3850);
DISPLAY 0.872340 (-1577 3850);
PAINT GREEN (-1577 3850);
DISPLAY INVISIBLE (-1577 3850);
FORCEADD TAP..6
(-1575 4000);
FORCEPROP 3 LASTPIN (-1525 4000) SIG_NAME M_B_MA<12>
J 0
(-1515 4010);
DISPLAY 0.659574 (-1515 4010);
PAINT MONO (-1515 4010);
DISPLAY INVISIBLE (-1515 4010);
FORCEPROP 1 LASTPIN (-1525 4000) BN 12
J 0
(-1575 4010);
DISPLAY 0.617021 (-1575 4010);
PAINT PINK (-1575 4010);
FORCEPROP 2 LAST CDS_LIB mstr_standard
J 2
(-1575 4000);
DISPLAY 0.787234 (-1575 4000);
PAINT MONO (-1575 4000);
DISPLAY INVISIBLE (-1575 4000);
FORCEPROP 1 LAST BODY_TYPE PLUMBING
J 0
(-1575 3950);
DISPLAY 1.234043 (-1575 3950);
PAINT GREEN (-1575 3950);
DISPLAY INVISIBLE (-1575 3950);
FORCEPROP 1 LAST HDL_TAP TRUE
J 0
(-1250 3875);
DISPLAY 1.234043 (-1250 3875);
PAINT GREEN (-1250 3875);
DISPLAY INVISIBLE (-1250 3875);
FORCEPROP 1 LAST PATH I119
J 0
(-1577 4000);
DISPLAY 0.872340 (-1577 4000);
PAINT GREEN (-1577 4000);
DISPLAY INVISIBLE (-1577 4000);
FORCEADD OFFPAGE..1
(-2225 1200);
FORCEPROP 2 LAST $XR0 99 
J 0
(-2476 1200);
DISPLAY 0.638298 (-2476 1200);
PAINT MONO (-2476 1200);
FORCEPROP 2 LAST $XR1 43 
J 0
(-2566 1200);
DISPLAY 0.638298 (-2566 1200);
PAINT MONO (-2566 1200);
FORCEPROP 2 LAST $XR2 44 
J 0
(-2656 1200);
DISPLAY 0.638298 (-2656 1200);
PAINT MONO (-2656 1200);
FORCEPROP 2 LAST $XR3 45 
J 0
(-2746 1200);
DISPLAY 0.638298 (-2746 1200);
PAINT MONO (-2746 1200);
FORCEPROP 2 LAST $XR4 47 
J 0
(-2836 1200);
DISPLAY 0.638298 (-2836 1200);
PAINT MONO (-2836 1200);
FORCEPROP 2 LAST $XR5 48 
J 0
(-2926 1200);
DISPLAY 0.638298 (-2926 1200);
PAINT MONO (-2926 1200);
FORCEPROP 2 LAST CDS_LIB mstr_standard
J 0
(-2225 1200);
DISPLAY 0.787234 (-2225 1200);
PAINT MONO (-2225 1200);
DISPLAY INVISIBLE (-2225 1200);
FORCEPROP 1 LAST OFFPAGE TRUE
J 0
(-1900 1075);
DISPLAY 0.936170 (-1900 1075);
PAINT GREEN (-1900 1075);
DISPLAY INVISIBLE (-1900 1075);
FORCEPROP 1 LAST COMMENT_BODY TRUE
J 0
(-2100 1100);
DISPLAY 0.936170 (-2100 1100);
PAINT GREEN (-2100 1100);
DISPLAY INVISIBLE (-2100 1100);
FORCEPROP 2 LAST PATH I12
J 0
(-2475 1250);
DISPLAY 1.021277 (-2475 1250);
PAINT ORANGE (-2475 1250);
DISPLAY INVISIBLE (-2475 1250);
FORCEADD TAP..6
(-1575 4050);
FORCEPROP 3 LASTPIN (-1525 4050) SIG_NAME M_B_MA<13>
J 0
(-1515 4060);
DISPLAY 0.659574 (-1515 4060);
PAINT MONO (-1515 4060);
DISPLAY INVISIBLE (-1515 4060);
FORCEPROP 1 LASTPIN (-1525 4050) BN 13
J 0
(-1575 4060);
DISPLAY 0.617021 (-1575 4060);
PAINT PINK (-1575 4060);
FORCEPROP 2 LAST CDS_LIB mstr_standard
J 2
(-1575 4050);
DISPLAY 0.787234 (-1575 4050);
PAINT MONO (-1575 4050);
DISPLAY INVISIBLE (-1575 4050);
FORCEPROP 1 LAST BODY_TYPE PLUMBING
J 0
(-1575 4000);
DISPLAY 1.234043 (-1575 4000);
PAINT GREEN (-1575 4000);
DISPLAY INVISIBLE (-1575 4000);
FORCEPROP 1 LAST HDL_TAP TRUE
J 0
(-1250 3925);
DISPLAY 1.234043 (-1250 3925);
PAINT GREEN (-1250 3925);
DISPLAY INVISIBLE (-1250 3925);
FORCEPROP 1 LAST PATH I120
J 0
(-1577 4050);
DISPLAY 0.872340 (-1577 4050);
PAINT GREEN (-1577 4050);
DISPLAY INVISIBLE (-1577 4050);
FORCEADD TAP..6
(-1575 4100);
FORCEPROP 3 LASTPIN (-1525 4100) SIG_NAME M_B_MA<14>
J 0
(-1515 4110);
DISPLAY 0.659574 (-1515 4110);
PAINT MONO (-1515 4110);
DISPLAY INVISIBLE (-1515 4110);
FORCEPROP 1 LASTPIN (-1525 4100) BN 14
J 0
(-1575 4110);
DISPLAY 0.617021 (-1575 4110);
PAINT PINK (-1575 4110);
FORCEPROP 2 LAST CDS_LIB mstr_standard
J 2
(-1575 4100);
DISPLAY 0.787234 (-1575 4100);
PAINT MONO (-1575 4100);
DISPLAY INVISIBLE (-1575 4100);
FORCEPROP 1 LAST BODY_TYPE PLUMBING
J 0
(-1575 4050);
DISPLAY 1.234043 (-1575 4050);
PAINT GREEN (-1575 4050);
DISPLAY INVISIBLE (-1575 4050);
FORCEPROP 1 LAST HDL_TAP TRUE
J 0
(-1250 3975);
DISPLAY 1.234043 (-1250 3975);
PAINT GREEN (-1250 3975);
DISPLAY INVISIBLE (-1250 3975);
FORCEPROP 1 LAST PATH I121
J 0
(-1577 4100);
DISPLAY 0.872340 (-1577 4100);
PAINT GREEN (-1577 4100);
DISPLAY INVISIBLE (-1577 4100);
FORCEADD TAP..6
(-1575 4200);
FORCEPROP 3 LASTPIN (-1525 4200) SIG_NAME M_B_MA<16>
J 0
(-1515 4210);
DISPLAY 0.659574 (-1515 4210);
PAINT MONO (-1515 4210);
DISPLAY INVISIBLE (-1515 4210);
FORCEPROP 1 LASTPIN (-1525 4200) BN 16
J 0
(-1575 4210);
DISPLAY 0.617021 (-1575 4210);
PAINT PINK (-1575 4210);
FORCEPROP 2 LAST CDS_LIB mstr_standard
J 2
(-1575 4200);
DISPLAY 0.787234 (-1575 4200);
PAINT MONO (-1575 4200);
DISPLAY INVISIBLE (-1575 4200);
FORCEPROP 1 LAST BODY_TYPE PLUMBING
J 0
(-1575 4150);
DISPLAY 1.234043 (-1575 4150);
PAINT GREEN (-1575 4150);
DISPLAY INVISIBLE (-1575 4150);
FORCEPROP 1 LAST HDL_TAP TRUE
J 0
(-1250 4075);
DISPLAY 1.234043 (-1250 4075);
PAINT GREEN (-1250 4075);
DISPLAY INVISIBLE (-1250 4075);
FORCEPROP 1 LAST PATH I122
J 0
(-1577 4200);
DISPLAY 0.872340 (-1577 4200);
PAINT GREEN (-1577 4200);
DISPLAY INVISIBLE (-1577 4200);
FORCEADD TAP..6
(-1575 4150);
FORCEPROP 3 LASTPIN (-1525 4150) SIG_NAME M_B_MA<15>
J 0
(-1515 4160);
DISPLAY 0.659574 (-1515 4160);
PAINT MONO (-1515 4160);
DISPLAY INVISIBLE (-1515 4160);
FORCEPROP 1 LASTPIN (-1525 4150) BN 15
J 0
(-1575 4160);
DISPLAY 0.617021 (-1575 4160);
PAINT PINK (-1575 4160);
FORCEPROP 2 LAST CDS_LIB mstr_standard
J 2
(-1575 4150);
DISPLAY 0.787234 (-1575 4150);
PAINT MONO (-1575 4150);
DISPLAY INVISIBLE (-1575 4150);
FORCEPROP 1 LAST BODY_TYPE PLUMBING
J 0
(-1575 4100);
DISPLAY 1.234043 (-1575 4100);
PAINT GREEN (-1575 4100);
DISPLAY INVISIBLE (-1575 4100);
FORCEPROP 1 LAST HDL_TAP TRUE
J 0
(-1250 4025);
DISPLAY 1.234043 (-1250 4025);
PAINT GREEN (-1250 4025);
DISPLAY INVISIBLE (-1250 4025);
FORCEPROP 1 LAST PATH I123
J 0
(-1577 4150);
DISPLAY 0.872340 (-1577 4150);
PAINT GREEN (-1577 4150);
DISPLAY INVISIBLE (-1577 4150);
FORCEADD TAP..6
(-1575 4250);
FORCEPROP 3 LASTPIN (-1525 4250) SIG_NAME M_B_MA<17>
J 0
(-1515 4260);
DISPLAY 0.659574 (-1515 4260);
PAINT MONO (-1515 4260);
DISPLAY INVISIBLE (-1515 4260);
FORCEPROP 1 LASTPIN (-1525 4250) BN 17
J 0
(-1575 4260);
DISPLAY 0.617021 (-1575 4260);
PAINT PINK (-1575 4260);
FORCEPROP 2 LAST CDS_LIB mstr_standard
J 0
(-1575 4250);
DISPLAY 0.787234 (-1575 4250);
PAINT MONO (-1575 4250);
DISPLAY INVISIBLE (-1575 4250);
FORCEPROP 1 LAST BODY_TYPE PLUMBING
J 0
(-1575 4200);
DISPLAY 1.234043 (-1575 4200);
PAINT GREEN (-1575 4200);
DISPLAY INVISIBLE (-1575 4200);
FORCEPROP 1 LAST HDL_TAP TRUE
J 0
(-1250 4125);
DISPLAY 1.234043 (-1250 4125);
PAINT GREEN (-1250 4125);
DISPLAY INVISIBLE (-1250 4125);
FORCEPROP 1 LAST PATH I124
J 0
(-1577 4250);
DISPLAY 0.872340 (-1577 4250);
PAINT GREEN (-1577 4250);
DISPLAY INVISIBLE (-1577 4250);
FORCEADD TAP..6
R 2
(-75 3750);
FORCEPROP 3 LASTPIN (-125 3750) SIG_NAME M_B_DQ<53>
J 0
(-115 3760);
DISPLAY 0.659574 (-115 3760);
PAINT MONO (-115 3760);
DISPLAY INVISIBLE (-115 3760);
FORCEPROP 1 LASTPIN (-125 3750) BN 53
J 2
(-75 3760);
DISPLAY 0.617021 (-75 3760);
PAINT PINK (-75 3760);
FORCEPROP 2 LAST CDS_LIB mstr_standard
J 2
(-75 3750);
DISPLAY 0.787234 (-75 3750);
PAINT MONO (-75 3750);
DISPLAY INVISIBLE (-75 3750);
FORCEPROP 1 LAST BODY_TYPE PLUMBING
J 2
(-75 3700);
DISPLAY 1.234043 (-75 3700);
PAINT GREEN (-75 3700);
DISPLAY INVISIBLE (-75 3700);
FORCEPROP 1 LAST HDL_TAP TRUE
J 2
(-400 3625);
DISPLAY 1.234043 (-400 3625);
PAINT GREEN (-400 3625);
DISPLAY INVISIBLE (-400 3625);
FORCEPROP 1 LAST PATH I125
J 2
(-73 3750);
DISPLAY 0.872340 (-73 3750);
PAINT GREEN (-73 3750);
DISPLAY INVISIBLE (-73 3750);
FORCEADD TAP..6
R 2
(-75 3850);
FORCEPROP 3 LASTPIN (-125 3850) SIG_NAME M_B_DQ<55>
J 0
(-115 3860);
DISPLAY 0.659574 (-115 3860);
PAINT MONO (-115 3860);
DISPLAY INVISIBLE (-115 3860);
FORCEPROP 1 LASTPIN (-125 3850) BN 55
J 2
(-75 3860);
DISPLAY 0.617021 (-75 3860);
PAINT PINK (-75 3860);
FORCEPROP 2 LAST CDS_LIB mstr_standard
J 2
(-75 3850);
DISPLAY 0.787234 (-75 3850);
PAINT MONO (-75 3850);
DISPLAY INVISIBLE (-75 3850);
FORCEPROP 1 LAST BODY_TYPE PLUMBING
J 2
(-75 3800);
DISPLAY 1.234043 (-75 3800);
PAINT GREEN (-75 3800);
DISPLAY INVISIBLE (-75 3800);
FORCEPROP 1 LAST HDL_TAP TRUE
J 2
(-400 3725);
DISPLAY 1.234043 (-400 3725);
PAINT GREEN (-400 3725);
DISPLAY INVISIBLE (-400 3725);
FORCEPROP 1 LAST PATH I126
J 2
(-73 3850);
DISPLAY 0.872340 (-73 3850);
PAINT GREEN (-73 3850);
DISPLAY INVISIBLE (-73 3850);
FORCEADD TAP..6
R 2
(-75 3800);
FORCEPROP 3 LASTPIN (-125 3800) SIG_NAME M_B_DQ<54>
J 0
(-115 3810);
DISPLAY 0.659574 (-115 3810);
PAINT MONO (-115 3810);
DISPLAY INVISIBLE (-115 3810);
FORCEPROP 1 LASTPIN (-125 3800) BN 54
J 2
(-75 3810);
DISPLAY 0.617021 (-75 3810);
PAINT PINK (-75 3810);
FORCEPROP 2 LAST CDS_LIB mstr_standard
J 2
(-75 3800);
DISPLAY 0.787234 (-75 3800);
PAINT MONO (-75 3800);
DISPLAY INVISIBLE (-75 3800);
FORCEPROP 1 LAST BODY_TYPE PLUMBING
J 2
(-75 3750);
DISPLAY 1.234043 (-75 3750);
PAINT GREEN (-75 3750);
DISPLAY INVISIBLE (-75 3750);
FORCEPROP 1 LAST HDL_TAP TRUE
J 2
(-400 3675);
DISPLAY 1.234043 (-400 3675);
PAINT GREEN (-400 3675);
DISPLAY INVISIBLE (-400 3675);
FORCEPROP 1 LAST PATH I127
J 2
(-73 3800);
DISPLAY 0.872340 (-73 3800);
PAINT GREEN (-73 3800);
DISPLAY INVISIBLE (-73 3800);
FORCEADD TAP..6
R 2
(-75 3950);
FORCEPROP 3 LASTPIN (-125 3950) SIG_NAME M_B_DQ<57>
J 0
(-115 3960);
DISPLAY 0.659574 (-115 3960);
PAINT MONO (-115 3960);
DISPLAY INVISIBLE (-115 3960);
FORCEPROP 1 LASTPIN (-125 3950) BN 57
J 2
(-75 3960);
DISPLAY 0.617021 (-75 3960);
PAINT PINK (-75 3960);
FORCEPROP 2 LAST CDS_LIB mstr_standard
J 2
(-75 3950);
DISPLAY 0.787234 (-75 3950);
PAINT MONO (-75 3950);
DISPLAY INVISIBLE (-75 3950);
FORCEPROP 1 LAST BODY_TYPE PLUMBING
J 2
(-75 3900);
DISPLAY 1.234043 (-75 3900);
PAINT GREEN (-75 3900);
DISPLAY INVISIBLE (-75 3900);
FORCEPROP 1 LAST HDL_TAP TRUE
J 2
(-400 3825);
DISPLAY 1.234043 (-400 3825);
PAINT GREEN (-400 3825);
DISPLAY INVISIBLE (-400 3825);
FORCEPROP 1 LAST PATH I128
J 2
(-73 3950);
DISPLAY 0.872340 (-73 3950);
PAINT GREEN (-73 3950);
DISPLAY INVISIBLE (-73 3950);
FORCEADD TAP..6
R 2
(-75 3900);
FORCEPROP 3 LASTPIN (-125 3900) SIG_NAME M_B_DQ<56>
J 0
(-115 3910);
DISPLAY 0.659574 (-115 3910);
PAINT MONO (-115 3910);
DISPLAY INVISIBLE (-115 3910);
FORCEPROP 1 LASTPIN (-125 3900) BN 56
J 2
(-75 3910);
DISPLAY 0.617021 (-75 3910);
PAINT PINK (-75 3910);
FORCEPROP 2 LAST CDS_LIB mstr_standard
J 2
(-75 3900);
DISPLAY 0.787234 (-75 3900);
PAINT MONO (-75 3900);
DISPLAY INVISIBLE (-75 3900);
FORCEPROP 1 LAST BODY_TYPE PLUMBING
J 2
(-75 3850);
DISPLAY 1.234043 (-75 3850);
PAINT GREEN (-75 3850);
DISPLAY INVISIBLE (-75 3850);
FORCEPROP 1 LAST HDL_TAP TRUE
J 2
(-400 3775);
DISPLAY 1.234043 (-400 3775);
PAINT GREEN (-400 3775);
DISPLAY INVISIBLE (-400 3775);
FORCEPROP 1 LAST PATH I129
J 2
(-73 3900);
DISPLAY 0.872340 (-73 3900);
PAINT GREEN (-73 3900);
DISPLAY INVISIBLE (-73 3900);
FORCEADD OFFPAGE..6
(-2225 1250);
FORCEPROP 2 LAST $XR0 43 
J 0
(-2474 1250);
DISPLAY 0.638298 (-2474 1250);
PAINT MONO (-2474 1250);
FORCEPROP 2 LAST $XR1 44 
J 0
(-2564 1250);
DISPLAY 0.638298 (-2564 1250);
PAINT MONO (-2564 1250);
FORCEPROP 2 LAST $XR2 45 
J 0
(-2654 1250);
DISPLAY 0.638298 (-2654 1250);
PAINT MONO (-2654 1250);
FORCEPROP 2 LAST $XR3 47 
J 0
(-2744 1250);
DISPLAY 0.638298 (-2744 1250);
PAINT MONO (-2744 1250);
FORCEPROP 2 LAST $XR4 48 
J 0
(-2834 1250);
DISPLAY 0.638298 (-2834 1250);
PAINT MONO (-2834 1250);
FORCEPROP 2 LAST $XR5 99 
J 0
(-2924 1250);
DISPLAY 0.638298 (-2924 1250);
PAINT MONO (-2924 1250);
FORCEPROP 2 LASTPIN (-2175 1250) SIG_NAME SMB_DDR_ABC_VPP_SDA
J 0
(-2135 1260);
DISPLAY 0.617021 (-2135 1260);
PAINT ORANGE (-2135 1260);
FORCEPROP 2 LAST CDS_LIB mstr_standard
J 0
(-2225 1250);
DISPLAY 0.787234 (-2225 1250);
PAINT MONO (-2225 1250);
DISPLAY INVISIBLE (-2225 1250);
FORCEPROP 1 LAST OFFPAGE TRUE
J 0
(-1900 1125);
DISPLAY 0.936170 (-1900 1125);
PAINT GREEN (-1900 1125);
DISPLAY INVISIBLE (-1900 1125);
FORCEPROP 1 LAST COMMENT_BODY TRUE
J 0
(-2125 1175);
DISPLAY 0.936170 (-2125 1175);
PAINT GREEN (-2125 1175);
DISPLAY INVISIBLE (-2125 1175);
FORCEPROP 2 LAST PATH I13
J 0
(-2450 1300);
DISPLAY 1.021277 (-2450 1300);
PAINT ORANGE (-2450 1300);
DISPLAY INVISIBLE (-2450 1300);
FORCEADD TAP..6
R 2
(-75 4000);
FORCEPROP 3 LASTPIN (-125 4000) SIG_NAME M_B_DQ<58>
J 0
(-115 4010);
DISPLAY 0.659574 (-115 4010);
PAINT MONO (-115 4010);
DISPLAY INVISIBLE (-115 4010);
FORCEPROP 1 LASTPIN (-125 4000) BN 58
J 2
(-75 4010);
DISPLAY 0.617021 (-75 4010);
PAINT PINK (-75 4010);
FORCEPROP 2 LAST CDS_LIB mstr_standard
J 2
(-75 4000);
DISPLAY 0.787234 (-75 4000);
PAINT MONO (-75 4000);
DISPLAY INVISIBLE (-75 4000);
FORCEPROP 1 LAST BODY_TYPE PLUMBING
J 2
(-75 3950);
DISPLAY 1.234043 (-75 3950);
PAINT GREEN (-75 3950);
DISPLAY INVISIBLE (-75 3950);
FORCEPROP 1 LAST HDL_TAP TRUE
J 2
(-400 3875);
DISPLAY 1.234043 (-400 3875);
PAINT GREEN (-400 3875);
DISPLAY INVISIBLE (-400 3875);
FORCEPROP 1 LAST PATH I130
J 2
(-73 4000);
DISPLAY 0.872340 (-73 4000);
PAINT GREEN (-73 4000);
DISPLAY INVISIBLE (-73 4000);
FORCEADD TAP..6
R 2
(-75 4050);
FORCEPROP 3 LASTPIN (-125 4050) SIG_NAME M_B_DQ<59>
J 0
(-115 4060);
DISPLAY 0.659574 (-115 4060);
PAINT MONO (-115 4060);
DISPLAY INVISIBLE (-115 4060);
FORCEPROP 1 LASTPIN (-125 4050) BN 59
J 2
(-75 4060);
DISPLAY 0.617021 (-75 4060);
PAINT PINK (-75 4060);
FORCEPROP 2 LAST CDS_LIB mstr_standard
J 2
(-75 4050);
DISPLAY 0.787234 (-75 4050);
PAINT MONO (-75 4050);
DISPLAY INVISIBLE (-75 4050);
FORCEPROP 1 LAST BODY_TYPE PLUMBING
J 2
(-75 4000);
DISPLAY 1.234043 (-75 4000);
PAINT GREEN (-75 4000);
DISPLAY INVISIBLE (-75 4000);
FORCEPROP 1 LAST HDL_TAP TRUE
J 2
(-400 3925);
DISPLAY 1.234043 (-400 3925);
PAINT GREEN (-400 3925);
DISPLAY INVISIBLE (-400 3925);
FORCEPROP 1 LAST PATH I131
J 2
(-73 4050);
DISPLAY 0.872340 (-73 4050);
PAINT GREEN (-73 4050);
DISPLAY INVISIBLE (-73 4050);
FORCEADD TAP..6
R 2
(-75 4100);
FORCEPROP 3 LASTPIN (-125 4100) SIG_NAME M_B_DQ<60>
J 0
(-115 4110);
DISPLAY 0.659574 (-115 4110);
PAINT MONO (-115 4110);
DISPLAY INVISIBLE (-115 4110);
FORCEPROP 1 LASTPIN (-125 4100) BN 60
J 2
(-75 4110);
DISPLAY 0.617021 (-75 4110);
PAINT PINK (-75 4110);
FORCEPROP 2 LAST CDS_LIB mstr_standard
J 2
(-75 4100);
DISPLAY 0.787234 (-75 4100);
PAINT MONO (-75 4100);
DISPLAY INVISIBLE (-75 4100);
FORCEPROP 1 LAST BODY_TYPE PLUMBING
J 2
(-75 4050);
DISPLAY 1.234043 (-75 4050);
PAINT GREEN (-75 4050);
DISPLAY INVISIBLE (-75 4050);
FORCEPROP 1 LAST HDL_TAP TRUE
J 2
(-400 3975);
DISPLAY 1.234043 (-400 3975);
PAINT GREEN (-400 3975);
DISPLAY INVISIBLE (-400 3975);
FORCEPROP 1 LAST PATH I132
J 2
(-73 4100);
DISPLAY 0.872340 (-73 4100);
PAINT GREEN (-73 4100);
DISPLAY INVISIBLE (-73 4100);
FORCEADD TAP..6
R 2
(-75 4150);
FORCEPROP 3 LASTPIN (-125 4150) SIG_NAME M_B_DQ<61>
J 0
(-115 4160);
DISPLAY 0.659574 (-115 4160);
PAINT MONO (-115 4160);
DISPLAY INVISIBLE (-115 4160);
FORCEPROP 1 LASTPIN (-125 4150) BN 61
J 2
(-75 4160);
DISPLAY 0.617021 (-75 4160);
PAINT PINK (-75 4160);
FORCEPROP 2 LAST CDS_LIB mstr_standard
J 2
(-75 4150);
DISPLAY 0.787234 (-75 4150);
PAINT MONO (-75 4150);
DISPLAY INVISIBLE (-75 4150);
FORCEPROP 1 LAST BODY_TYPE PLUMBING
J 2
(-75 4100);
DISPLAY 1.234043 (-75 4100);
PAINT GREEN (-75 4100);
DISPLAY INVISIBLE (-75 4100);
FORCEPROP 1 LAST HDL_TAP TRUE
J 2
(-400 4025);
DISPLAY 1.234043 (-400 4025);
PAINT GREEN (-400 4025);
DISPLAY INVISIBLE (-400 4025);
FORCEPROP 1 LAST PATH I133
J 2
(-73 4150);
DISPLAY 0.872340 (-73 4150);
PAINT GREEN (-73 4150);
DISPLAY INVISIBLE (-73 4150);
FORCEADD TAP..6
R 2
(-75 4200);
FORCEPROP 3 LASTPIN (-125 4200) SIG_NAME M_B_DQ<62>
J 0
(-115 4210);
DISPLAY 0.659574 (-115 4210);
PAINT MONO (-115 4210);
DISPLAY INVISIBLE (-115 4210);
FORCEPROP 1 LASTPIN (-125 4200) BN 62
J 2
(-75 4210);
DISPLAY 0.617021 (-75 4210);
PAINT PINK (-75 4210);
FORCEPROP 2 LAST CDS_LIB mstr_standard
J 2
(-75 4200);
DISPLAY 0.787234 (-75 4200);
PAINT MONO (-75 4200);
DISPLAY INVISIBLE (-75 4200);
FORCEPROP 1 LAST BODY_TYPE PLUMBING
J 2
(-75 4150);
DISPLAY 1.234043 (-75 4150);
PAINT GREEN (-75 4150);
DISPLAY INVISIBLE (-75 4150);
FORCEPROP 1 LAST HDL_TAP TRUE
J 2
(-400 4075);
DISPLAY 1.234043 (-400 4075);
PAINT GREEN (-400 4075);
DISPLAY INVISIBLE (-400 4075);
FORCEPROP 1 LAST PATH I134
J 2
(-73 4200);
DISPLAY 0.872340 (-73 4200);
PAINT GREEN (-73 4200);
DISPLAY INVISIBLE (-73 4200);
FORCEADD TAP..6
R 2
(-75 4250);
FORCEPROP 3 LASTPIN (-125 4250) SIG_NAME M_B_DQ<63>
J 0
(-115 4260);
DISPLAY 0.659574 (-115 4260);
PAINT MONO (-115 4260);
DISPLAY INVISIBLE (-115 4260);
FORCEPROP 1 LASTPIN (-125 4250) BN 63
J 2
(-75 4260);
DISPLAY 0.617021 (-75 4260);
PAINT PINK (-75 4260);
FORCEPROP 2 LAST CDS_LIB mstr_standard
J 2
(-75 4250);
DISPLAY 0.787234 (-75 4250);
PAINT MONO (-75 4250);
DISPLAY INVISIBLE (-75 4250);
FORCEPROP 1 LAST BODY_TYPE PLUMBING
J 2
(-75 4200);
DISPLAY 1.234043 (-75 4200);
PAINT GREEN (-75 4200);
DISPLAY INVISIBLE (-75 4200);
FORCEPROP 1 LAST HDL_TAP TRUE
J 2
(-400 4125);
DISPLAY 1.234043 (-400 4125);
PAINT GREEN (-400 4125);
DISPLAY INVISIBLE (-400 4125);
FORCEPROP 1 LAST PATH I135
J 2
(-73 4250);
DISPLAY 0.872340 (-73 4250);
PAINT GREEN (-73 4250);
DISPLAY INVISIBLE (-73 4250);
FORCEADD OFFPAGE..3
(475 4300);
FORCEPROP 2 LAST $XR0 24 
J 0
(689 4300);
DISPLAY 0.638298 (689 4300);
PAINT MONO (689 4300);
FORCEPROP 2 LAST $XR1 45 
J 0
(779 4300);
DISPLAY 0.638298 (779 4300);
PAINT MONO (779 4300);
FORCEPROP 2 LAST CDS_LIB mstr_standard
J 0
(475 4300);
DISPLAY 0.787234 (475 4300);
PAINT MONO (475 4300);
DISPLAY INVISIBLE (475 4300);
FORCEPROP 1 LAST OFFPAGE TRUE
J 0
(800 4175);
DISPLAY 0.936170 (800 4175);
PAINT GREEN (800 4175);
DISPLAY INVISIBLE (800 4175);
FORCEPROP 1 LAST COMMENT_BODY TRUE
J 0
(425 4200);
DISPLAY 0.936170 (425 4200);
PAINT GREEN (425 4200);
DISPLAY INVISIBLE (425 4200);
FORCEPROP 2 LAST PATH I136
J 0
(700 4350);
DISPLAY 1.021277 (700 4350);
PAINT ORANGE (700 4350);
DISPLAY INVISIBLE (700 4350);
FORCEADD GND..1
R 2
(2725 950);
FORCEPROP 3 LASTPIN (2725 1000) SIG_NAME GND\g
J 0
(2735 1010);
DISPLAY 0.659574 (2735 1010);
PAINT MONO (2735 1010);
DISPLAY INVISIBLE (2735 1010);
FORCEPROP 1 LAST VOLTAGE 0
J 0
(2725 950);
PAINT SKYBLUE (2725 950);
DISPLAY INVISIBLE (2725 950);
FORCEPROP 1 LAST SIZE 1B
J 2
(2650 900);
DISPLAY 1.170213 (2650 900);
PAINT GREEN (2650 900);
DISPLAY INVISIBLE (2650 900);
FORCEPROP 2 LAST CDS_LIB mstr_symbols
J 0
(2725 950);
DISPLAY 0.787234 (2725 950);
PAINT MONO (2725 950);
DISPLAY INVISIBLE (2725 950);
FORCEPROP 2 LAST BOM_COST MEM
J 0
(2725 955);
PAINT ORANGE (2725 955);
DISPLAY INVISIBLE (2725 955);
FORCEPROP 1 LAST BODY_TYPE PLUMBING
J 2
(2770 907);
DISPLAY 0.340426 (2770 907);
PAINT GREEN (2770 907);
DISPLAY INVISIBLE (2770 907);
FORCEPROP 1 LAST PATH I137
J 2
(2650 950);
DISPLAY 0.872340 (2650 950);
PAINT AQUA (2650 950);
DISPLAY INVISIBLE (2650 950);
FORCEPROP 2 LAST ROOM DDR4_CH_A
J 0
(2725 955);
PAINT ORANGE (2725 955);
DISPLAY INVISIBLE (2725 955);
FORCEPROP 1 LAST HDL_POWER GND
J 2
(2725 1100);
DISPLAY 0.553191 (2725 1100);
PAINT GREEN (2725 1100);
DISPLAY INVISIBLE (2725 1100);
FORCEADD SCONN288_H44441003..3
(3425 2250);
FORCEPROP 1 LAST LOCATION J6U1
J 0
(2975 3650);
DISPLAY 0.617021 (2975 3650);
PAINT AQUA (2975 3650);
FORCEPROP 1 LAST PART_NUMBER H44441-003
J 0
(2975 900);
DISPLAY 0.617021 (2975 900);
PAINT BLUE (2975 900);
FORCEPROP 1 LAST MATERIAL SCONN
J 0
(2975 3600);
DISPLAY 0.617021 (2975 3600);
PAINT SKYBLUE (2975 3600);
FORCEPROP 2 LASTPIN (2925 3400) $PN 2
J 2
(2915 3410);
DISPLAY 0.617021 (2915 3410);
PAINT ORANGE (2915 3410);
FORCEPROP 2 LASTPIN (2925 3350) $PN 4
J 2
(2915 3360);
DISPLAY 0.617021 (2915 3360);
PAINT ORANGE (2915 3360);
FORCEPROP 2 LASTPIN (2925 3300) $PN 6
J 2
(2915 3310);
DISPLAY 0.617021 (2915 3310);
PAINT ORANGE (2915 3310);
FORCEPROP 2 LASTPIN (2925 3250) $PN 9
J 2
(2915 3260);
DISPLAY 0.617021 (2915 3260);
PAINT ORANGE (2915 3260);
FORCEPROP 2 LASTPIN (2925 3200) $PN 11
J 2
(2915 3210);
DISPLAY 0.617021 (2915 3210);
PAINT ORANGE (2915 3210);
FORCEPROP 2 LASTPIN (2925 3150) $PN 13
J 2
(2915 3160);
DISPLAY 0.617021 (2915 3160);
PAINT ORANGE (2915 3160);
FORCEPROP 2 LASTPIN (2925 3100) $PN 15
J 2
(2915 3110);
DISPLAY 0.617021 (2915 3110);
PAINT ORANGE (2915 3110);
FORCEPROP 2 LASTPIN (2925 3050) $PN 17
J 2
(2915 3060);
DISPLAY 0.617021 (2915 3060);
PAINT ORANGE (2915 3060);
FORCEPROP 2 LASTPIN (2925 3000) $PN 20
J 2
(2915 3010);
DISPLAY 0.617021 (2915 3010);
PAINT ORANGE (2915 3010);
FORCEPROP 2 LASTPIN (2925 2950) $PN 22
J 2
(2915 2960);
DISPLAY 0.617021 (2915 2960);
PAINT ORANGE (2915 2960);
FORCEPROP 2 LASTPIN (2925 2900) $PN 24
J 2
(2915 2910);
DISPLAY 0.617021 (2915 2910);
PAINT ORANGE (2915 2910);
FORCEPROP 2 LASTPIN (2925 2850) $PN 26
J 2
(2915 2860);
DISPLAY 0.617021 (2915 2860);
PAINT ORANGE (2915 2860);
FORCEPROP 2 LASTPIN (2925 2800) $PN 28
J 2
(2915 2810);
DISPLAY 0.617021 (2915 2810);
PAINT ORANGE (2915 2810);
FORCEPROP 2 LASTPIN (2925 2750) $PN 31
J 2
(2915 2760);
DISPLAY 0.617021 (2915 2760);
PAINT ORANGE (2915 2760);
FORCEPROP 2 LASTPIN (2925 2700) $PN 33
J 2
(2915 2710);
DISPLAY 0.617021 (2915 2710);
PAINT ORANGE (2915 2710);
FORCEPROP 2 LASTPIN (2925 2650) $PN 35
J 2
(2915 2660);
DISPLAY 0.617021 (2915 2660);
PAINT ORANGE (2915 2660);
FORCEPROP 2 LASTPIN (2925 2600) $PN 37
J 2
(2915 2610);
DISPLAY 0.617021 (2915 2610);
PAINT ORANGE (2915 2610);
FORCEPROP 2 LASTPIN (2925 2550) $PN 39
J 2
(2915 2560);
DISPLAY 0.617021 (2915 2560);
PAINT ORANGE (2915 2560);
FORCEPROP 2 LASTPIN (2925 2500) $PN 42
J 2
(2915 2510);
DISPLAY 0.617021 (2915 2510);
PAINT ORANGE (2915 2510);
FORCEPROP 2 LASTPIN (2925 2450) $PN 44
J 2
(2915 2460);
DISPLAY 0.617021 (2915 2460);
PAINT ORANGE (2915 2460);
FORCEPROP 2 LASTPIN (2925 2400) $PN 46
J 2
(2915 2410);
DISPLAY 0.617021 (2915 2410);
PAINT ORANGE (2915 2410);
FORCEPROP 2 LASTPIN (2925 2350) $PN 48
J 2
(2915 2360);
DISPLAY 0.617021 (2915 2360);
PAINT ORANGE (2915 2360);
FORCEPROP 2 LASTPIN (2925 2300) $PN 50
J 2
(2915 2310);
DISPLAY 0.617021 (2915 2310);
PAINT ORANGE (2915 2310);
FORCEPROP 2 LASTPIN (2925 2250) $PN 53
J 2
(2915 2260);
DISPLAY 0.617021 (2915 2260);
PAINT ORANGE (2915 2260);
FORCEPROP 2 LASTPIN (2925 2200) $PN 55
J 2
(2915 2210);
DISPLAY 0.617021 (2915 2210);
PAINT ORANGE (2915 2210);
FORCEPROP 2 LASTPIN (2925 2150) $PN 57
J 2
(2915 2160);
DISPLAY 0.617021 (2915 2160);
PAINT ORANGE (2915 2160);
FORCEPROP 2 LASTPIN (2925 2100) $PN 94
J 2
(2915 2110);
DISPLAY 0.617021 (2915 2110);
PAINT ORANGE (2915 2110);
FORCEPROP 2 LASTPIN (2925 2050) $PN 96
J 2
(2915 2060);
DISPLAY 0.617021 (2915 2060);
PAINT ORANGE (2915 2060);
FORCEPROP 2 LASTPIN (2925 2000) $PN 98
J 2
(2915 2010);
DISPLAY 0.617021 (2915 2010);
PAINT ORANGE (2915 2010);
FORCEPROP 2 LASTPIN (2925 1950) $PN 101
J 2
(2915 1960);
DISPLAY 0.617021 (2915 1960);
PAINT ORANGE (2915 1960);
FORCEPROP 2 LASTPIN (2925 1900) $PN 103
J 2
(2915 1910);
DISPLAY 0.617021 (2915 1910);
PAINT ORANGE (2915 1910);
FORCEPROP 2 LASTPIN (2925 1850) $PN 105
J 2
(2915 1860);
DISPLAY 0.617021 (2915 1860);
PAINT ORANGE (2915 1860);
FORCEPROP 2 LASTPIN (2925 1800) $PN 107
J 2
(2915 1810);
DISPLAY 0.617021 (2915 1810);
PAINT ORANGE (2915 1810);
FORCEPROP 2 LASTPIN (2925 1750) $PN 109
J 2
(2915 1760);
DISPLAY 0.617021 (2915 1760);
PAINT ORANGE (2915 1760);
FORCEPROP 2 LASTPIN (2925 1700) $PN 112
J 2
(2915 1710);
DISPLAY 0.617021 (2915 1710);
PAINT ORANGE (2915 1710);
FORCEPROP 2 LASTPIN (2925 1650) $PN 114
J 2
(2915 1660);
DISPLAY 0.617021 (2915 1660);
PAINT ORANGE (2915 1660);
FORCEPROP 2 LASTPIN (2925 1600) $PN 116
J 2
(2915 1610);
DISPLAY 0.617021 (2915 1610);
PAINT ORANGE (2915 1610);
FORCEPROP 2 LASTPIN (2925 1550) $PN 118
J 2
(2915 1560);
DISPLAY 0.617021 (2915 1560);
PAINT ORANGE (2915 1560);
FORCEPROP 2 LASTPIN (2925 1500) $PN 120
J 2
(2915 1510);
DISPLAY 0.617021 (2915 1510);
PAINT ORANGE (2915 1510);
FORCEPROP 2 LASTPIN (2925 1450) $PN 123
J 2
(2915 1460);
DISPLAY 0.617021 (2915 1460);
PAINT ORANGE (2915 1460);
FORCEPROP 2 LASTPIN (2925 1400) $PN 125
J 2
(2915 1410);
DISPLAY 0.617021 (2915 1410);
PAINT ORANGE (2915 1410);
FORCEPROP 2 LASTPIN (2925 1350) $PN 127
J 2
(2915 1360);
DISPLAY 0.617021 (2915 1360);
PAINT ORANGE (2915 1360);
FORCEPROP 2 LASTPIN (2925 1300) $PN 129
J 2
(2915 1310);
DISPLAY 0.617021 (2915 1310);
PAINT ORANGE (2915 1310);
FORCEPROP 2 LASTPIN (2925 1250) $PN 131
J 2
(2915 1260);
DISPLAY 0.617021 (2915 1260);
PAINT ORANGE (2915 1260);
FORCEPROP 2 LASTPIN (2925 1200) $PN 134
J 2
(2915 1210);
DISPLAY 0.617021 (2915 1210);
PAINT ORANGE (2915 1210);
FORCEPROP 2 LASTPIN (2925 1150) $PN 136
J 2
(2915 1160);
DISPLAY 0.617021 (2915 1160);
PAINT ORANGE (2915 1160);
FORCEPROP 2 LASTPIN (2925 1100) $PN 138
J 2
(2915 1110);
DISPLAY 0.617021 (2915 1110);
PAINT ORANGE (2915 1110);
FORCEPROP 2 LASTPIN (3925 3400) $PN 147
J 0
(3935 3410);
DISPLAY 0.617021 (3935 3410);
PAINT ORANGE (3935 3410);
FORCEPROP 2 LASTPIN (3925 3350) $PN 149
J 0
(3935 3360);
DISPLAY 0.617021 (3935 3360);
PAINT ORANGE (3935 3360);
FORCEPROP 2 LASTPIN (3925 3300) $PN 151
J 0
(3935 3310);
DISPLAY 0.617021 (3935 3310);
PAINT ORANGE (3935 3310);
FORCEPROP 2 LASTPIN (3925 3250) $PN 154
J 0
(3935 3260);
DISPLAY 0.617021 (3935 3260);
PAINT ORANGE (3935 3260);
FORCEPROP 2 LASTPIN (3925 3200) $PN 156
J 0
(3935 3210);
DISPLAY 0.617021 (3935 3210);
PAINT ORANGE (3935 3210);
FORCEPROP 2 LASTPIN (3925 3150) $PN 158
J 0
(3935 3160);
DISPLAY 0.617021 (3935 3160);
PAINT ORANGE (3935 3160);
FORCEPROP 2 LASTPIN (3925 3100) $PN 160
J 0
(3935 3110);
DISPLAY 0.617021 (3935 3110);
PAINT ORANGE (3935 3110);
FORCEPROP 2 LASTPIN (3925 3050) $PN 162
J 0
(3935 3060);
DISPLAY 0.617021 (3935 3060);
PAINT ORANGE (3935 3060);
FORCEPROP 2 LASTPIN (3925 3000) $PN 165
J 0
(3935 3010);
DISPLAY 0.617021 (3935 3010);
PAINT ORANGE (3935 3010);
FORCEPROP 2 LASTPIN (3925 2950) $PN 167
J 0
(3935 2960);
DISPLAY 0.617021 (3935 2960);
PAINT ORANGE (3935 2960);
FORCEPROP 2 LASTPIN (3925 2900) $PN 169
J 0
(3935 2910);
DISPLAY 0.617021 (3935 2910);
PAINT ORANGE (3935 2910);
FORCEPROP 2 LASTPIN (3925 2850) $PN 171
J 0
(3935 2860);
DISPLAY 0.617021 (3935 2860);
PAINT ORANGE (3935 2860);
FORCEPROP 2 LASTPIN (3925 2800) $PN 173
J 0
(3935 2810);
DISPLAY 0.617021 (3935 2810);
PAINT ORANGE (3935 2810);
FORCEPROP 2 LASTPIN (3925 2750) $PN 176
J 0
(3935 2760);
DISPLAY 0.617021 (3935 2760);
PAINT ORANGE (3935 2760);
FORCEPROP 2 LASTPIN (3925 2700) $PN 178
J 0
(3935 2710);
DISPLAY 0.617021 (3935 2710);
PAINT ORANGE (3935 2710);
FORCEPROP 2 LASTPIN (3925 2650) $PN 180
J 0
(3935 2660);
DISPLAY 0.617021 (3935 2660);
PAINT ORANGE (3935 2660);
FORCEPROP 2 LASTPIN (3925 2600) $PN 182
J 0
(3935 2610);
DISPLAY 0.617021 (3935 2610);
PAINT ORANGE (3935 2610);
FORCEPROP 2 LASTPIN (3925 2550) $PN 184
J 0
(3935 2560);
DISPLAY 0.617021 (3935 2560);
PAINT ORANGE (3935 2560);
FORCEPROP 2 LASTPIN (3925 2500) $PN 187
J 0
(3935 2510);
DISPLAY 0.617021 (3935 2510);
PAINT ORANGE (3935 2510);
FORCEPROP 2 LASTPIN (3925 2450) $PN 189
J 0
(3935 2460);
DISPLAY 0.617021 (3935 2460);
PAINT ORANGE (3935 2460);
FORCEPROP 2 LASTPIN (3925 2400) $PN 191
J 0
(3935 2410);
DISPLAY 0.617021 (3935 2410);
PAINT ORANGE (3935 2410);
FORCEPROP 2 LASTPIN (3925 2350) $PN 193
J 0
(3935 2360);
DISPLAY 0.617021 (3935 2360);
PAINT ORANGE (3935 2360);
FORCEPROP 2 LASTPIN (3925 2300) $PN 195
J 0
(3935 2310);
DISPLAY 0.617021 (3935 2310);
PAINT ORANGE (3935 2310);
FORCEPROP 2 LASTPIN (3925 2250) $PN 198
J 0
(3935 2260);
DISPLAY 0.617021 (3935 2260);
PAINT ORANGE (3935 2260);
FORCEPROP 2 LASTPIN (3925 2200) $PN 200
J 0
(3935 2210);
DISPLAY 0.617021 (3935 2210);
PAINT ORANGE (3935 2210);
FORCEPROP 2 LASTPIN (3925 2150) $PN 202
J 0
(3935 2160);
DISPLAY 0.617021 (3935 2160);
PAINT ORANGE (3935 2160);
FORCEPROP 2 LASTPIN (3925 2100) $PN 239
J 0
(3935 2110);
DISPLAY 0.617021 (3935 2110);
PAINT ORANGE (3935 2110);
FORCEPROP 2 LASTPIN (3925 2050) $PN 241
J 0
(3935 2060);
DISPLAY 0.617021 (3935 2060);
PAINT ORANGE (3935 2060);
FORCEPROP 2 LASTPIN (3925 2000) $PN 243
J 0
(3935 2010);
DISPLAY 0.617021 (3935 2010);
PAINT ORANGE (3935 2010);
FORCEPROP 2 LASTPIN (3925 1950) $PN 246
J 0
(3935 1960);
DISPLAY 0.617021 (3935 1960);
PAINT ORANGE (3935 1960);
FORCEPROP 2 LASTPIN (3925 1900) $PN 248
J 0
(3935 1910);
DISPLAY 0.617021 (3935 1910);
PAINT ORANGE (3935 1910);
FORCEPROP 2 LASTPIN (3925 1850) $PN 250
J 0
(3935 1860);
DISPLAY 0.617021 (3935 1860);
PAINT ORANGE (3935 1860);
FORCEPROP 2 LASTPIN (3925 1800) $PN 252
J 0
(3935 1810);
DISPLAY 0.617021 (3935 1810);
PAINT ORANGE (3935 1810);
FORCEPROP 2 LASTPIN (3925 1750) $PN 254
J 0
(3935 1760);
DISPLAY 0.617021 (3935 1760);
PAINT ORANGE (3935 1760);
FORCEPROP 2 LASTPIN (3925 1700) $PN 257
J 0
(3935 1710);
DISPLAY 0.617021 (3935 1710);
PAINT ORANGE (3935 1710);
FORCEPROP 2 LASTPIN (3925 1650) $PN 259
J 0
(3935 1660);
DISPLAY 0.617021 (3935 1660);
PAINT ORANGE (3935 1660);
FORCEPROP 2 LASTPIN (3925 1600) $PN 261
J 0
(3935 1610);
DISPLAY 0.617021 (3935 1610);
PAINT ORANGE (3935 1610);
FORCEPROP 2 LASTPIN (3925 1550) $PN 263
J 0
(3935 1560);
DISPLAY 0.617021 (3935 1560);
PAINT ORANGE (3935 1560);
FORCEPROP 2 LASTPIN (3925 1500) $PN 265
J 0
(3935 1510);
DISPLAY 0.617021 (3935 1510);
PAINT ORANGE (3935 1510);
FORCEPROP 2 LASTPIN (3925 1450) $PN 268
J 0
(3935 1460);
DISPLAY 0.617021 (3935 1460);
PAINT ORANGE (3935 1460);
FORCEPROP 2 LASTPIN (3925 1400) $PN 270
J 0
(3935 1410);
DISPLAY 0.617021 (3935 1410);
PAINT ORANGE (3935 1410);
FORCEPROP 2 LASTPIN (3925 1350) $PN 272
J 0
(3935 1360);
DISPLAY 0.617021 (3935 1360);
PAINT ORANGE (3935 1360);
FORCEPROP 2 LASTPIN (3925 1300) $PN 274
J 0
(3935 1310);
DISPLAY 0.617021 (3935 1310);
PAINT ORANGE (3935 1310);
FORCEPROP 2 LASTPIN (3925 1250) $PN 276
J 0
(3935 1260);
DISPLAY 0.617021 (3935 1260);
PAINT ORANGE (3935 1260);
FORCEPROP 2 LASTPIN (3925 1200) $PN 279
J 0
(3935 1210);
DISPLAY 0.617021 (3935 1210);
PAINT ORANGE (3935 1210);
FORCEPROP 2 LASTPIN (3925 1150) $PN 281
J 0
(3935 1160);
DISPLAY 0.617021 (3935 1160);
PAINT ORANGE (3935 1160);
FORCEPROP 2 LASTPIN (3925 1100) $PN 283
J 0
(3935 1110);
DISPLAY 0.617021 (3935 1110);
PAINT ORANGE (3935 1110);
FORCEPROP 1 LAST PACK_TYPE PIP
J 0
(2975 3700);
PAINT SKYBLUE (2975 3700);
DISPLAY INVISIBLE (2975 3700);
FORCEPROP 2 LAST BOM_COST MEM
J 0
(3425 2250);
PAINT ORANGE (3425 2250);
DISPLAY INVISIBLE (3425 2250);
FORCEPROP 2 LAST CDS_LIB mstr_sconn
J 0
(3425 2250);
PAINT ORANGE (3425 2250);
DISPLAY INVISIBLE (3425 2250);
FORCEPROP 2 LAST SEC_TYPE PIP
J 0
(2975 3700);
DISPLAY 1.021277 (2975 3700);
PAINT ORANGE (2975 3700);
DISPLAY INVISIBLE (2975 3700);
FORCEPROP 2 LAST SEC 3
J 0
(2975 3700);
DISPLAY 0.680851 (2975 3700);
PAINT MONO (2975 3700);
DISPLAY INVISIBLE (2975 3700);
FORCEPROP 2 LAST CDS_LOCATION J6U1
J 0
(2975 3650);
DISPLAY 0.617021 (2975 3650);
PAINT AQUA (2975 3650);
DISPLAY INVISIBLE (2975 3650);
FORCEPROP 1 LAST PATH I138
J 0
(3425 3600);
PAINT GREEN (3425 3600);
DISPLAY INVISIBLE (3425 3600);
FORCEPROP 2 LAST ROOM DDR4_CH_B
J 0
(3425 2250);
PAINT ORANGE (3425 2250);
DISPLAY INVISIBLE (3425 2250);
FORCEADD SCONN288_H44441003..1
(-825 2600);
FORCEPROP 2 LASTPIN (-1325 2300) $PN 87
J 2
(-1335 2310);
DISPLAY 0.617021 (-1335 2310);
PAINT ORANGE (-1335 2310);
FORCEPROP 1 LAST LOCATION J6U1
J 0
(-1275 4500);
DISPLAY 0.617021 (-1275 4500);
PAINT AQUA (-1275 4500);
FORCEPROP 1 LAST PART_NUMBER H44441-003
J 0
(-1275 600);
DISPLAY 0.617021 (-1275 600);
PAINT BLUE (-1275 600);
FORCEPROP 1 LAST MATERIAL SCONN
J 0
(-1275 4450);
DISPLAY 0.617021 (-1275 4450);
PAINT SKYBLUE (-1275 4450);
FORCEPROP 2 LASTPIN (-1325 1100) $PN 146
J 2
(-1335 1110);
DISPLAY 0.617021 (-1335 1110);
PAINT ORANGE (-1335 1110);
FORCEPROP 2 LASTPIN (-1325 1450) $PN 284
J 2
(-1335 1460);
DISPLAY 0.617021 (-1335 1460);
PAINT ORANGE (-1335 1460);
FORCEPROP 2 LASTPIN (-1325 1250) $PN 285
J 2
(-1335 1260);
DISPLAY 0.617021 (-1335 1260);
PAINT ORANGE (-1335 1260);
FORCEPROP 2 LASTPIN (-1325 1200) $PN 141
J 2
(-1335 1210);
DISPLAY 0.617021 (-1335 1210);
PAINT ORANGE (-1335 1210);
FORCEPROP 2 LASTPIN (-1325 800) $PN 230
J 2
(-1335 810);
DISPLAY 0.617021 (-1335 810);
PAINT ORANGE (-1335 810);
FORCEPROP 2 LASTPIN (-1325 1400) $PN 238
J 2
(-1335 1410);
DISPLAY 0.617021 (-1335 1410);
PAINT ORANGE (-1335 1410);
FORCEPROP 2 LASTPIN (-1325 1350) $PN 140
J 2
(-1335 1360);
DISPLAY 0.617021 (-1335 1360);
PAINT ORANGE (-1335 1360);
FORCEPROP 2 LASTPIN (-1325 1300) $PN 139
J 2
(-1335 1310);
DISPLAY 0.617021 (-1335 1310);
PAINT ORANGE (-1335 1310);
FORCEPROP 2 LASTPIN (-1325 2750) $PN 237
J 2
(-1335 2760);
DISPLAY 0.617021 (-1335 2760);
PAINT ORANGE (-1335 2760);
FORCEPROP 2 LASTPIN (-1325 2700) $PN 93
J 2
(-1335 2710);
DISPLAY 0.617021 (-1335 2710);
PAINT ORANGE (-1335 2710);
FORCEPROP 2 LASTPIN (-1325 2650) $PN 89
J 2
(-1335 2660);
DISPLAY 0.617021 (-1335 2660);
PAINT ORANGE (-1335 2660);
FORCEPROP 2 LASTPIN (-1325 2600) $PN 84
J 2
(-1335 2610);
DISPLAY 0.617021 (-1335 2610);
PAINT ORANGE (-1335 2610);
FORCEPROP 2 LASTPIN (-1325 1000) $PN 144
J 2
(-1335 1010);
DISPLAY 0.617021 (-1335 1010);
PAINT ORANGE (-1335 1010);
FORCEPROP 2 LASTPIN (-1325 950) $PN 227
J 2
(-1335 960);
DISPLAY 0.617021 (-1335 960);
PAINT ORANGE (-1335 960);
FORCEPROP 2 LASTPIN (-1325 900) $PN 205
J 2
(-1335 910);
DISPLAY 0.617021 (-1335 910);
PAINT ORANGE (-1335 910);
FORCEPROP 2 LASTPIN (-1325 1700) $PN 58
J 2
(-1335 1710);
DISPLAY 0.617021 (-1335 1710);
PAINT ORANGE (-1335 1710);
FORCEPROP 2 LASTPIN (-1325 1750) $PN 222
J 2
(-1335 1760);
DISPLAY 0.617021 (-1335 1760);
PAINT ORANGE (-1335 1760);
FORCEPROP 2 LASTPIN (-1325 2350) $PN 91
J 2
(-1335 2360);
DISPLAY 0.617021 (-1335 2360);
PAINT ORANGE (-1335 2360);
FORCEPROP 2 LASTPIN (-1325 1650) $PN 78
J 2
(-1335 1660);
DISPLAY 0.617021 (-1335 1660);
PAINT ORANGE (-1335 1660);
FORCEPROP 2 LASTPIN (-325 4250) $PN 280
J 0
(-315 4260);
DISPLAY 0.617021 (-315 4260);
PAINT ORANGE (-315 4260);
FORCEPROP 2 LASTPIN (-325 4200) $PN 135
J 0
(-315 4210);
DISPLAY 0.617021 (-315 4210);
PAINT ORANGE (-315 4210);
FORCEPROP 2 LASTPIN (-325 4150) $PN 273
J 0
(-315 4160);
DISPLAY 0.617021 (-315 4160);
PAINT ORANGE (-315 4160);
FORCEPROP 2 LASTPIN (-325 4100) $PN 128
J 0
(-315 4110);
DISPLAY 0.617021 (-315 4110);
PAINT ORANGE (-315 4110);
FORCEPROP 2 LASTPIN (-325 4050) $PN 282
J 0
(-315 4060);
DISPLAY 0.617021 (-315 4060);
PAINT ORANGE (-315 4060);
FORCEPROP 2 LASTPIN (-325 4000) $PN 137
J 0
(-315 4010);
DISPLAY 0.617021 (-315 4010);
PAINT ORANGE (-315 4010);
FORCEPROP 2 LASTPIN (-325 3950) $PN 275
J 0
(-315 3960);
DISPLAY 0.617021 (-315 3960);
PAINT ORANGE (-315 3960);
FORCEPROP 2 LASTPIN (-325 3900) $PN 130
J 0
(-315 3910);
DISPLAY 0.617021 (-315 3910);
PAINT ORANGE (-315 3910);
FORCEPROP 2 LASTPIN (-325 3850) $PN 269
J 0
(-315 3860);
DISPLAY 0.617021 (-315 3860);
PAINT ORANGE (-315 3860);
FORCEPROP 2 LASTPIN (-325 3800) $PN 124
J 0
(-315 3810);
DISPLAY 0.617021 (-315 3810);
PAINT ORANGE (-315 3810);
FORCEPROP 2 LASTPIN (-325 3750) $PN 262
J 0
(-315 3760);
DISPLAY 0.617021 (-315 3760);
PAINT ORANGE (-315 3760);
FORCEPROP 2 LASTPIN (-325 3700) $PN 117
J 0
(-315 3710);
DISPLAY 0.617021 (-315 3710);
PAINT ORANGE (-315 3710);
FORCEPROP 2 LASTPIN (-325 3650) $PN 271
J 0
(-315 3660);
DISPLAY 0.617021 (-315 3660);
PAINT ORANGE (-315 3660);
FORCEPROP 2 LASTPIN (-325 3600) $PN 126
J 0
(-315 3610);
DISPLAY 0.617021 (-315 3610);
PAINT ORANGE (-315 3610);
FORCEPROP 2 LASTPIN (-325 3550) $PN 264
J 0
(-315 3560);
DISPLAY 0.617021 (-315 3560);
PAINT ORANGE (-315 3560);
FORCEPROP 2 LASTPIN (-325 3500) $PN 119
J 0
(-315 3510);
DISPLAY 0.617021 (-315 3510);
PAINT ORANGE (-315 3510);
FORCEPROP 2 LASTPIN (-325 3450) $PN 258
J 0
(-315 3460);
DISPLAY 0.617021 (-315 3460);
PAINT ORANGE (-315 3460);
FORCEPROP 2 LASTPIN (-325 3400) $PN 113
J 0
(-315 3410);
DISPLAY 0.617021 (-315 3410);
PAINT ORANGE (-315 3410);
FORCEPROP 2 LASTPIN (-325 3350) $PN 251
J 0
(-315 3360);
DISPLAY 0.617021 (-315 3360);
PAINT ORANGE (-315 3360);
FORCEPROP 2 LASTPIN (-325 3300) $PN 106
J 0
(-315 3310);
DISPLAY 0.617021 (-315 3310);
PAINT ORANGE (-315 3310);
FORCEPROP 2 LASTPIN (-325 3250) $PN 260
J 0
(-315 3260);
DISPLAY 0.617021 (-315 3260);
PAINT ORANGE (-315 3260);
FORCEPROP 2 LASTPIN (-325 3200) $PN 115
J 0
(-315 3210);
DISPLAY 0.617021 (-315 3210);
PAINT ORANGE (-315 3210);
FORCEPROP 2 LASTPIN (-325 3150) $PN 253
J 0
(-315 3160);
DISPLAY 0.617021 (-315 3160);
PAINT ORANGE (-315 3160);
FORCEPROP 2 LASTPIN (-325 3100) $PN 108
J 0
(-315 3110);
DISPLAY 0.617021 (-315 3110);
PAINT ORANGE (-315 3110);
FORCEPROP 2 LASTPIN (-325 3050) $PN 247
J 0
(-315 3060);
DISPLAY 0.617021 (-315 3060);
PAINT ORANGE (-315 3060);
FORCEPROP 2 LASTPIN (-325 3000) $PN 102
J 0
(-315 3010);
DISPLAY 0.617021 (-315 3010);
PAINT ORANGE (-315 3010);
FORCEPROP 2 LASTPIN (-325 2950) $PN 240
J 0
(-315 2960);
DISPLAY 0.617021 (-315 2960);
PAINT ORANGE (-315 2960);
FORCEPROP 2 LASTPIN (-325 2900) $PN 95
J 0
(-315 2910);
DISPLAY 0.617021 (-315 2910);
PAINT ORANGE (-315 2910);
FORCEPROP 2 LASTPIN (-325 2850) $PN 249
J 0
(-315 2860);
DISPLAY 0.617021 (-315 2860);
PAINT ORANGE (-315 2860);
FORCEPROP 2 LASTPIN (-325 2800) $PN 104
J 0
(-315 2810);
DISPLAY 0.617021 (-315 2810);
PAINT ORANGE (-315 2810);
FORCEPROP 2 LASTPIN (-325 2750) $PN 242
J 0
(-315 2760);
DISPLAY 0.617021 (-315 2760);
PAINT ORANGE (-315 2760);
FORCEPROP 2 LASTPIN (-325 2700) $PN 97
J 0
(-315 2710);
DISPLAY 0.617021 (-315 2710);
PAINT ORANGE (-315 2710);
FORCEPROP 2 LASTPIN (-325 2650) $PN 188
J 0
(-315 2660);
DISPLAY 0.617021 (-315 2660);
PAINT ORANGE (-315 2660);
FORCEPROP 2 LASTPIN (-325 2600) $PN 43
J 0
(-315 2610);
DISPLAY 0.617021 (-315 2610);
PAINT ORANGE (-315 2610);
FORCEPROP 2 LASTPIN (-325 2550) $PN 181
J 0
(-315 2560);
DISPLAY 0.617021 (-315 2560);
PAINT ORANGE (-315 2560);
FORCEPROP 2 LASTPIN (-325 2500) $PN 36
J 0
(-315 2510);
DISPLAY 0.617021 (-315 2510);
PAINT ORANGE (-315 2510);
FORCEPROP 2 LASTPIN (-325 2450) $PN 190
J 0
(-315 2460);
DISPLAY 0.617021 (-315 2460);
PAINT ORANGE (-315 2460);
FORCEPROP 2 LASTPIN (-325 2400) $PN 45
J 0
(-315 2410);
DISPLAY 0.617021 (-315 2410);
PAINT ORANGE (-315 2410);
FORCEPROP 2 LASTPIN (-325 2350) $PN 183
J 0
(-315 2360);
DISPLAY 0.617021 (-315 2360);
PAINT ORANGE (-315 2360);
FORCEPROP 2 LASTPIN (-325 2300) $PN 38
J 0
(-315 2310);
DISPLAY 0.617021 (-315 2310);
PAINT ORANGE (-315 2310);
FORCEPROP 2 LASTPIN (-325 2250) $PN 177
J 0
(-315 2260);
DISPLAY 0.617021 (-315 2260);
PAINT ORANGE (-315 2260);
FORCEPROP 2 LASTPIN (-325 2200) $PN 32
J 0
(-315 2210);
DISPLAY 0.617021 (-315 2210);
PAINT ORANGE (-315 2210);
FORCEPROP 2 LASTPIN (-325 2150) $PN 170
J 0
(-315 2160);
DISPLAY 0.617021 (-315 2160);
PAINT ORANGE (-315 2160);
FORCEPROP 2 LASTPIN (-325 2100) $PN 25
J 0
(-315 2110);
DISPLAY 0.617021 (-315 2110);
PAINT ORANGE (-315 2110);
FORCEPROP 2 LASTPIN (-325 2050) $PN 179
J 0
(-315 2060);
DISPLAY 0.617021 (-315 2060);
PAINT ORANGE (-315 2060);
FORCEPROP 2 LASTPIN (-325 2000) $PN 34
J 0
(-315 2010);
DISPLAY 0.617021 (-315 2010);
PAINT ORANGE (-315 2010);
FORCEPROP 2 LASTPIN (-325 1950) $PN 172
J 0
(-315 1960);
DISPLAY 0.617021 (-315 1960);
PAINT ORANGE (-315 1960);
FORCEPROP 2 LASTPIN (-325 1900) $PN 27
J 0
(-315 1910);
DISPLAY 0.617021 (-315 1910);
PAINT ORANGE (-315 1910);
FORCEPROP 2 LASTPIN (-325 1850) $PN 166
J 0
(-315 1860);
DISPLAY 0.617021 (-315 1860);
PAINT ORANGE (-315 1860);
FORCEPROP 2 LASTPIN (-325 1800) $PN 21
J 0
(-315 1810);
DISPLAY 0.617021 (-315 1810);
PAINT ORANGE (-315 1810);
FORCEPROP 2 LASTPIN (-325 1750) $PN 159
J 0
(-315 1760);
DISPLAY 0.617021 (-315 1760);
PAINT ORANGE (-315 1760);
FORCEPROP 2 LASTPIN (-325 1700) $PN 14
J 0
(-315 1710);
DISPLAY 0.617021 (-315 1710);
PAINT ORANGE (-315 1710);
FORCEPROP 2 LASTPIN (-325 1650) $PN 168
J 0
(-315 1660);
DISPLAY 0.617021 (-315 1660);
PAINT ORANGE (-315 1660);
FORCEPROP 2 LASTPIN (-325 1600) $PN 23
J 0
(-315 1610);
DISPLAY 0.617021 (-315 1610);
PAINT ORANGE (-315 1610);
FORCEPROP 2 LASTPIN (-325 1550) $PN 161
J 0
(-315 1560);
DISPLAY 0.617021 (-315 1560);
PAINT ORANGE (-315 1560);
FORCEPROP 2 LASTPIN (-325 1500) $PN 16
J 0
(-315 1510);
DISPLAY 0.617021 (-315 1510);
PAINT ORANGE (-315 1510);
FORCEPROP 2 LASTPIN (-325 1450) $PN 155
J 0
(-315 1460);
DISPLAY 0.617021 (-315 1460);
PAINT ORANGE (-315 1460);
FORCEPROP 2 LASTPIN (-325 1400) $PN 10
J 0
(-315 1410);
DISPLAY 0.617021 (-315 1410);
PAINT ORANGE (-315 1410);
FORCEPROP 2 LASTPIN (-325 1350) $PN 148
J 0
(-315 1360);
DISPLAY 0.617021 (-315 1360);
PAINT ORANGE (-315 1360);
FORCEPROP 2 LASTPIN (-325 1300) $PN 3
J 0
(-315 1310);
DISPLAY 0.617021 (-315 1310);
PAINT ORANGE (-315 1310);
FORCEPROP 2 LASTPIN (-325 1250) $PN 157
J 0
(-315 1260);
DISPLAY 0.617021 (-315 1260);
PAINT ORANGE (-315 1260);
FORCEPROP 2 LASTPIN (-325 1200) $PN 12
J 0
(-315 1210);
DISPLAY 0.617021 (-315 1210);
PAINT ORANGE (-315 1210);
FORCEPROP 2 LASTPIN (-325 1150) $PN 150
J 0
(-315 1160);
DISPLAY 0.617021 (-315 1160);
PAINT ORANGE (-315 1160);
FORCEPROP 2 LASTPIN (-325 1100) $PN 5
J 0
(-315 1110);
DISPLAY 0.617021 (-315 1110);
PAINT ORANGE (-315 1110);
FORCEPROP 2 LASTPIN (-1325 2500) $PN 203
J 2
(-1335 2510);
DISPLAY 0.617021 (-1335 2510);
PAINT ORANGE (-1335 2510);
FORCEPROP 2 LASTPIN (-1325 2450) $PN 60
J 2
(-1335 2460);
DISPLAY 0.617021 (-1335 2460);
PAINT ORANGE (-1335 2460);
FORCEPROP 2 LASTPIN (-1325 3050) $PN 218
J 2
(-1335 3060);
DISPLAY 0.617021 (-1335 3060);
PAINT ORANGE (-1335 3060);
FORCEPROP 2 LASTPIN (-1325 3000) $PN 219
J 2
(-1335 3010);
DISPLAY 0.617021 (-1335 3010);
PAINT ORANGE (-1335 3010);
FORCEPROP 2 LASTPIN (-1325 2950) $PN 74
J 2
(-1335 2960);
DISPLAY 0.617021 (-1335 2960);
PAINT ORANGE (-1335 2960);
FORCEPROP 2 LASTPIN (-1325 2900) $PN 75
J 2
(-1335 2910);
DISPLAY 0.617021 (-1335 2910);
PAINT ORANGE (-1335 2910);
FORCEPROP 2 LASTPIN (-1325 2200) $PN 199
J 2
(-1335 2210);
DISPLAY 0.617021 (-1335 2210);
PAINT ORANGE (-1335 2210);
FORCEPROP 2 LASTPIN (-1325 2150) $PN 54
J 2
(-1335 2160);
DISPLAY 0.617021 (-1335 2160);
PAINT ORANGE (-1335 2160);
FORCEPROP 2 LASTPIN (-1325 2100) $PN 192
J 2
(-1335 2110);
DISPLAY 0.617021 (-1335 2110);
PAINT ORANGE (-1335 2110);
FORCEPROP 2 LASTPIN (-1325 2050) $PN 47
J 2
(-1335 2060);
DISPLAY 0.617021 (-1335 2060);
PAINT ORANGE (-1335 2060);
FORCEPROP 2 LASTPIN (-1325 2000) $PN 201
J 2
(-1335 2010);
DISPLAY 0.617021 (-1335 2010);
PAINT ORANGE (-1335 2010);
FORCEPROP 2 LASTPIN (-1325 1950) $PN 56
J 2
(-1335 1960);
DISPLAY 0.617021 (-1335 1960);
PAINT ORANGE (-1335 1960);
FORCEPROP 2 LASTPIN (-1325 1900) $PN 194
J 2
(-1335 1910);
DISPLAY 0.617021 (-1335 1910);
PAINT ORANGE (-1335 1910);
FORCEPROP 2 LASTPIN (-1325 1850) $PN 49
J 2
(-1335 1860);
DISPLAY 0.617021 (-1335 1860);
PAINT ORANGE (-1335 1860);
FORCEPROP 2 LASTPIN (-1325 2800) $PN 235
J 2
(-1335 2810);
DISPLAY 0.617021 (-1335 2810);
PAINT ORANGE (-1335 2810);
FORCEPROP 2 LASTPIN (-1325 3200) $PN 207
J 2
(-1335 3210);
DISPLAY 0.617021 (-1335 3210);
PAINT ORANGE (-1335 3210);
FORCEPROP 2 LASTPIN (-1325 3150) $PN 63
J 2
(-1335 3160);
DISPLAY 0.617021 (-1335 3160);
PAINT ORANGE (-1335 3160);
FORCEPROP 2 LASTPIN (-1325 3300) $PN 224
J 2
(-1335 3310);
DISPLAY 0.617021 (-1335 3310);
PAINT ORANGE (-1335 3310);
FORCEPROP 2 LASTPIN (-1325 3250) $PN 81
J 2
(-1335 3260);
DISPLAY 0.617021 (-1335 3260);
PAINT ORANGE (-1335 3260);
FORCEPROP 2 LASTPIN (-1325 1600) $PN 208
J 2
(-1335 1610);
DISPLAY 0.617021 (-1335 1610);
PAINT ORANGE (-1335 1610);
FORCEPROP 2 LASTPIN (-1325 1550) $PN 62
J 2
(-1335 1560);
DISPLAY 0.617021 (-1335 1560);
PAINT ORANGE (-1335 1560);
FORCEPROP 2 LASTPIN (-1325 4250) $PN 234
J 2
(-1335 4260);
DISPLAY 0.617021 (-1335 4260);
PAINT ORANGE (-1335 4260);
FORCEPROP 2 LASTPIN (-1325 4200) $PN 82
J 2
(-1335 4210);
DISPLAY 0.617021 (-1335 4210);
PAINT ORANGE (-1335 4210);
FORCEPROP 2 LASTPIN (-1325 4150) $PN 86
J 2
(-1335 4160);
DISPLAY 0.617021 (-1335 4160);
PAINT ORANGE (-1335 4160);
FORCEPROP 2 LASTPIN (-1325 4100) $PN 228
J 2
(-1335 4110);
DISPLAY 0.617021 (-1335 4110);
PAINT ORANGE (-1335 4110);
FORCEPROP 2 LASTPIN (-1325 4050) $PN 232
J 2
(-1335 4060);
DISPLAY 0.617021 (-1335 4060);
PAINT ORANGE (-1335 4060);
FORCEPROP 2 LASTPIN (-1325 4000) $PN 65
J 2
(-1335 4010);
DISPLAY 0.617021 (-1335 4010);
PAINT ORANGE (-1335 4010);
FORCEPROP 2 LASTPIN (-1325 3950) $PN 210
J 2
(-1335 3960);
DISPLAY 0.617021 (-1335 3960);
PAINT ORANGE (-1335 3960);
FORCEPROP 2 LASTPIN (-1325 3900) $PN 225
J 2
(-1335 3910);
DISPLAY 0.617021 (-1335 3910);
PAINT ORANGE (-1335 3910);
FORCEPROP 2 LASTPIN (-1325 3850) $PN 66
J 2
(-1335 3860);
DISPLAY 0.617021 (-1335 3860);
PAINT ORANGE (-1335 3860);
FORCEPROP 2 LASTPIN (-1325 3800) $PN 68
J 2
(-1335 3810);
DISPLAY 0.617021 (-1335 3810);
PAINT ORANGE (-1335 3810);
FORCEPROP 2 LASTPIN (-1325 3750) $PN 211
J 2
(-1335 3760);
DISPLAY 0.617021 (-1335 3760);
PAINT ORANGE (-1335 3760);
FORCEPROP 2 LASTPIN (-1325 3700) $PN 69
J 2
(-1335 3710);
DISPLAY 0.617021 (-1335 3710);
PAINT ORANGE (-1335 3710);
FORCEPROP 2 LASTPIN (-1325 3650) $PN 213
J 2
(-1335 3660);
DISPLAY 0.617021 (-1335 3660);
PAINT ORANGE (-1335 3660);
FORCEPROP 2 LASTPIN (-1325 3600) $PN 214
J 2
(-1335 3610);
DISPLAY 0.617021 (-1335 3610);
PAINT ORANGE (-1335 3610);
FORCEPROP 2 LASTPIN (-1325 3550) $PN 71
J 2
(-1335 3560);
DISPLAY 0.617021 (-1335 3560);
PAINT ORANGE (-1335 3560);
FORCEPROP 2 LASTPIN (-1325 3500) $PN 216
J 2
(-1335 3510);
DISPLAY 0.617021 (-1335 3510);
PAINT ORANGE (-1335 3510);
FORCEPROP 2 LASTPIN (-1325 3450) $PN 72
J 2
(-1335 3460);
DISPLAY 0.617021 (-1335 3460);
PAINT ORANGE (-1335 3460);
FORCEPROP 2 LASTPIN (-1325 3400) $PN 79
J 2
(-1335 3410);
DISPLAY 0.617021 (-1335 3410);
PAINT ORANGE (-1335 3410);
FORCEPROP 1 LAST PACK_TYPE PIP
J 0
(-1275 4550);
PAINT SKYBLUE (-1275 4550);
DISPLAY INVISIBLE (-1275 4550);
FORCEPROP 2 LAST BOM_COST MEM
J 0
(-825 2600);
PAINT ORANGE (-825 2600);
DISPLAY INVISIBLE (-825 2600);
FORCEPROP 2 LAST CDS_LIB mstr_sconn
J 0
(-825 2600);
PAINT ORANGE (-825 2600);
DISPLAY INVISIBLE (-825 2600);
FORCEPROP 2 LAST SEC_TYPE PIP
J 0
(-1275 4550);
DISPLAY 1.021277 (-1275 4550);
PAINT ORANGE (-1275 4550);
DISPLAY INVISIBLE (-1275 4550);
FORCEPROP 2 LAST SEC 1
J 0
(-1275 4550);
DISPLAY 0.680851 (-1275 4550);
PAINT MONO (-1275 4550);
DISPLAY INVISIBLE (-1275 4550);
FORCEPROP 2 LAST CDS_LOCATION J6U1
J 0
(-1275 4500);
DISPLAY 0.617021 (-1275 4500);
PAINT AQUA (-1275 4500);
DISPLAY INVISIBLE (-1275 4500);
FORCEPROP 1 LAST PATH I14
J 0
(-825 4450);
PAINT GREEN (-825 4450);
DISPLAY INVISIBLE (-825 4450);
FORCEPROP 2 LAST ROOM DDR4_CH_B
J 0
(-825 2600);
PAINT ORANGE (-825 2600);
DISPLAY INVISIBLE (-825 2600);
FORCEADD TAP..6
R 2
(2325 3100);
FORCEPROP 3 LASTPIN (2275 3100) SIG_NAME M_B_DQS_DP<0>
J 0
(2285 3110);
DISPLAY 0.659574 (2285 3110);
PAINT MONO (2285 3110);
DISPLAY INVISIBLE (2285 3110);
FORCEPROP 1 LASTPIN (2275 3100) BN 0
J 2
(2325 3110);
DISPLAY 0.617021 (2325 3110);
PAINT PINK (2325 3110);
FORCEPROP 2 LAST CDS_LIB mstr_standard
J 0
(2325 3100);
DISPLAY 0.787234 (2325 3100);
PAINT MONO (2325 3100);
DISPLAY INVISIBLE (2325 3100);
FORCEPROP 1 LAST BODY_TYPE PLUMBING
J 2
(2325 3050);
DISPLAY 1.234043 (2325 3050);
PAINT GREEN (2325 3050);
DISPLAY INVISIBLE (2325 3050);
FORCEPROP 1 LAST HDL_TAP TRUE
J 2
(2000 2975);
DISPLAY 1.234043 (2000 2975);
PAINT GREEN (2000 2975);
DISPLAY INVISIBLE (2000 2975);
FORCEPROP 1 LAST PATH I142
J 2
(2327 3100);
DISPLAY 0.872340 (2327 3100);
PAINT GREEN (2327 3100);
DISPLAY INVISIBLE (2327 3100);
FORCEADD TAP..6
R 2
(2325 3200);
FORCEPROP 3 LASTPIN (2275 3200) SIG_NAME M_B_DQS_DP<1>
J 0
(2285 3210);
DISPLAY 0.659574 (2285 3210);
PAINT MONO (2285 3210);
DISPLAY INVISIBLE (2285 3210);
FORCEPROP 1 LASTPIN (2275 3200) BN 1
J 2
(2325 3210);
DISPLAY 0.617021 (2325 3210);
PAINT PINK (2325 3210);
FORCEPROP 2 LAST CDS_LIB mstr_standard
J 0
(2325 3200);
DISPLAY 0.787234 (2325 3200);
PAINT MONO (2325 3200);
DISPLAY INVISIBLE (2325 3200);
FORCEPROP 1 LAST BODY_TYPE PLUMBING
J 2
(2325 3150);
DISPLAY 1.234043 (2325 3150);
PAINT GREEN (2325 3150);
DISPLAY INVISIBLE (2325 3150);
FORCEPROP 1 LAST HDL_TAP TRUE
J 2
(2000 3075);
DISPLAY 1.234043 (2000 3075);
PAINT GREEN (2000 3075);
DISPLAY INVISIBLE (2000 3075);
FORCEPROP 1 LAST PATH I143
J 2
(2327 3200);
DISPLAY 0.872340 (2327 3200);
PAINT GREEN (2327 3200);
DISPLAY INVISIBLE (2327 3200);
FORCEADD TAP..6
R 2
(2525 3050);
FORCEPROP 3 LASTPIN (2475 3050) SIG_NAME M_B_DQS_DN<0>
J 0
(2485 3060);
DISPLAY 0.659574 (2485 3060);
PAINT MONO (2485 3060);
DISPLAY INVISIBLE (2485 3060);
FORCEPROP 1 LASTPIN (2475 3050) BN 0
J 2
(2525 3060);
DISPLAY 0.617021 (2525 3060);
PAINT PINK (2525 3060);
FORCEPROP 2 LAST CDS_LIB mstr_standard
J 0
(2525 3050);
DISPLAY 0.787234 (2525 3050);
PAINT MONO (2525 3050);
DISPLAY INVISIBLE (2525 3050);
FORCEPROP 1 LAST BODY_TYPE PLUMBING
J 2
(2525 3000);
DISPLAY 1.234043 (2525 3000);
PAINT GREEN (2525 3000);
DISPLAY INVISIBLE (2525 3000);
FORCEPROP 1 LAST HDL_TAP TRUE
J 2
(2200 2925);
DISPLAY 1.234043 (2200 2925);
PAINT GREEN (2200 2925);
DISPLAY INVISIBLE (2200 2925);
FORCEPROP 1 LAST PATH I144
J 2
(2527 3050);
DISPLAY 0.872340 (2527 3050);
PAINT GREEN (2527 3050);
DISPLAY INVISIBLE (2527 3050);
FORCEADD TAP..6
R 2
(2525 3150);
FORCEPROP 3 LASTPIN (2475 3150) SIG_NAME M_B_DQS_DN<1>
J 0
(2485 3160);
DISPLAY 0.659574 (2485 3160);
PAINT MONO (2485 3160);
DISPLAY INVISIBLE (2485 3160);
FORCEPROP 1 LASTPIN (2475 3150) BN 1
J 2
(2525 3160);
DISPLAY 0.617021 (2525 3160);
PAINT PINK (2525 3160);
FORCEPROP 2 LAST CDS_LIB mstr_standard
J 0
(2525 3150);
DISPLAY 0.787234 (2525 3150);
PAINT MONO (2525 3150);
DISPLAY INVISIBLE (2525 3150);
FORCEPROP 1 LAST BODY_TYPE PLUMBING
J 2
(2525 3100);
DISPLAY 1.234043 (2525 3100);
PAINT GREEN (2525 3100);
DISPLAY INVISIBLE (2525 3100);
FORCEPROP 1 LAST HDL_TAP TRUE
J 2
(2200 3025);
DISPLAY 1.234043 (2200 3025);
PAINT GREEN (2200 3025);
DISPLAY INVISIBLE (2200 3025);
FORCEPROP 1 LAST PATH I145
J 2
(2527 3150);
DISPLAY 0.872340 (2527 3150);
PAINT GREEN (2527 3150);
DISPLAY INVISIBLE (2527 3150);
FORCEADD TAP..6
R 2
(2325 3300);
FORCEPROP 3 LASTPIN (2275 3300) SIG_NAME M_B_DQS_DP<2>
J 0
(2285 3310);
DISPLAY 0.659574 (2285 3310);
PAINT MONO (2285 3310);
DISPLAY INVISIBLE (2285 3310);
FORCEPROP 1 LASTPIN (2275 3300) BN 2
J 2
(2325 3310);
DISPLAY 0.617021 (2325 3310);
PAINT PINK (2325 3310);
FORCEPROP 2 LAST CDS_LIB mstr_standard
J 0
(2325 3300);
DISPLAY 0.787234 (2325 3300);
PAINT MONO (2325 3300);
DISPLAY INVISIBLE (2325 3300);
FORCEPROP 1 LAST BODY_TYPE PLUMBING
J 2
(2325 3250);
DISPLAY 1.234043 (2325 3250);
PAINT GREEN (2325 3250);
DISPLAY INVISIBLE (2325 3250);
FORCEPROP 1 LAST HDL_TAP TRUE
J 2
(2000 3175);
DISPLAY 1.234043 (2000 3175);
PAINT GREEN (2000 3175);
DISPLAY INVISIBLE (2000 3175);
FORCEPROP 1 LAST PATH I146
J 2
(2327 3300);
DISPLAY 0.872340 (2327 3300);
PAINT GREEN (2327 3300);
DISPLAY INVISIBLE (2327 3300);
FORCEADD TAP..6
R 2
(2325 3400);
FORCEPROP 3 LASTPIN (2275 3400) SIG_NAME M_B_DQS_DP<3>
J 0
(2285 3410);
DISPLAY 0.659574 (2285 3410);
PAINT MONO (2285 3410);
DISPLAY INVISIBLE (2285 3410);
FORCEPROP 1 LASTPIN (2275 3400) BN 3
J 2
(2325 3410);
DISPLAY 0.617021 (2325 3410);
PAINT PINK (2325 3410);
FORCEPROP 2 LAST CDS_LIB mstr_standard
J 0
(2325 3400);
DISPLAY 0.787234 (2325 3400);
PAINT MONO (2325 3400);
DISPLAY INVISIBLE (2325 3400);
FORCEPROP 1 LAST BODY_TYPE PLUMBING
J 2
(2325 3350);
DISPLAY 1.234043 (2325 3350);
PAINT GREEN (2325 3350);
DISPLAY INVISIBLE (2325 3350);
FORCEPROP 1 LAST HDL_TAP TRUE
J 2
(2000 3275);
DISPLAY 1.234043 (2000 3275);
PAINT GREEN (2000 3275);
DISPLAY INVISIBLE (2000 3275);
FORCEPROP 1 LAST PATH I147
J 2
(2327 3400);
DISPLAY 0.872340 (2327 3400);
PAINT GREEN (2327 3400);
DISPLAY INVISIBLE (2327 3400);
FORCEADD TAP..6
R 2
(2325 3600);
FORCEPROP 3 LASTPIN (2275 3600) SIG_NAME M_B_DQS_DP<5>
J 0
(2285 3610);
DISPLAY 0.659574 (2285 3610);
PAINT MONO (2285 3610);
DISPLAY INVISIBLE (2285 3610);
FORCEPROP 1 LASTPIN (2275 3600) BN 5
J 2
(2325 3610);
DISPLAY 0.617021 (2325 3610);
PAINT PINK (2325 3610);
FORCEPROP 2 LAST CDS_LIB mstr_standard
J 0
(2325 3600);
DISPLAY 0.787234 (2325 3600);
PAINT MONO (2325 3600);
DISPLAY INVISIBLE (2325 3600);
FORCEPROP 1 LAST BODY_TYPE PLUMBING
J 2
(2325 3550);
DISPLAY 1.234043 (2325 3550);
PAINT GREEN (2325 3550);
DISPLAY INVISIBLE (2325 3550);
FORCEPROP 1 LAST HDL_TAP TRUE
J 2
(2000 3475);
DISPLAY 1.234043 (2000 3475);
PAINT GREEN (2000 3475);
DISPLAY INVISIBLE (2000 3475);
FORCEPROP 1 LAST PATH I148
J 2
(2327 3600);
DISPLAY 0.872340 (2327 3600);
PAINT GREEN (2327 3600);
DISPLAY INVISIBLE (2327 3600);
FORCEADD TAP..6
R 2
(2325 3500);
FORCEPROP 3 LASTPIN (2275 3500) SIG_NAME M_B_DQS_DP<4>
J 0
(2285 3510);
DISPLAY 0.659574 (2285 3510);
PAINT MONO (2285 3510);
DISPLAY INVISIBLE (2285 3510);
FORCEPROP 1 LASTPIN (2275 3500) BN 4
J 2
(2325 3510);
DISPLAY 0.617021 (2325 3510);
PAINT PINK (2325 3510);
FORCEPROP 2 LAST CDS_LIB mstr_standard
J 0
(2325 3500);
DISPLAY 0.787234 (2325 3500);
PAINT MONO (2325 3500);
DISPLAY INVISIBLE (2325 3500);
FORCEPROP 1 LAST BODY_TYPE PLUMBING
J 2
(2325 3450);
DISPLAY 1.234043 (2325 3450);
PAINT GREEN (2325 3450);
DISPLAY INVISIBLE (2325 3450);
FORCEPROP 1 LAST HDL_TAP TRUE
J 2
(2000 3375);
DISPLAY 1.234043 (2000 3375);
PAINT GREEN (2000 3375);
DISPLAY INVISIBLE (2000 3375);
FORCEPROP 1 LAST PATH I149
J 2
(2327 3500);
DISPLAY 0.872340 (2327 3500);
PAINT GREEN (2327 3500);
DISPLAY INVISIBLE (2327 3500);
FORCEADD OFFPAGE..1
(-2225 2150);
FORCEPROP 2 LAST $XR0 21 
J 0
(-2476 2150);
DISPLAY 0.638298 (-2476 2150);
PAINT MONO (-2476 2150);
FORCEPROP 2 LAST $XR1 43 
J 0
(-2566 2150);
DISPLAY 0.638298 (-2566 2150);
PAINT MONO (-2566 2150);
FORCEPROP 2 LAST $XR2 44 
J 0
(-2656 2150);
DISPLAY 0.638298 (-2656 2150);
PAINT MONO (-2656 2150);
FORCEPROP 2 LAST $XR3 45 
J 0
(-2746 2150);
DISPLAY 0.638298 (-2746 2150);
PAINT MONO (-2746 2150);
FORCEPROP 2 LAST $XR4 47 
J 0
(-2836 2150);
DISPLAY 0.638298 (-2836 2150);
PAINT MONO (-2836 2150);
FORCEPROP 2 LAST $XR5 48 
J 0
(-2926 2150);
DISPLAY 0.638298 (-2926 2150);
PAINT MONO (-2926 2150);
FORCEPROP 2 LAST CDS_LIB mstr_standard
J 0
(-2225 2150);
DISPLAY 0.787234 (-2225 2150);
PAINT MONO (-2225 2150);
DISPLAY INVISIBLE (-2225 2150);
FORCEPROP 1 LAST OFFPAGE TRUE
J 0
(-1900 2025);
DISPLAY 0.936170 (-1900 2025);
PAINT GREEN (-1900 2025);
DISPLAY INVISIBLE (-1900 2025);
FORCEPROP 1 LAST COMMENT_BODY TRUE
J 0
(-2100 2050);
DISPLAY 0.936170 (-2100 2050);
PAINT GREEN (-2100 2050);
DISPLAY INVISIBLE (-2100 2050);
FORCEPROP 2 LAST PATH I15
J 0
(-2425 2200);
DISPLAY 1.021277 (-2425 2200);
PAINT ORANGE (-2425 2200);
DISPLAY INVISIBLE (-2425 2200);
FORCEADD TAP..6
R 2
(2325 3700);
FORCEPROP 3 LASTPIN (2275 3700) SIG_NAME M_B_DQS_DP<6>
J 0
(2285 3710);
DISPLAY 0.659574 (2285 3710);
PAINT MONO (2285 3710);
DISPLAY INVISIBLE (2285 3710);
FORCEPROP 1 LASTPIN (2275 3700) BN 6
J 2
(2325 3710);
DISPLAY 0.617021 (2325 3710);
PAINT PINK (2325 3710);
FORCEPROP 2 LAST CDS_LIB mstr_standard
J 0
(2325 3700);
DISPLAY 0.787234 (2325 3700);
PAINT MONO (2325 3700);
DISPLAY INVISIBLE (2325 3700);
FORCEPROP 1 LAST BODY_TYPE PLUMBING
J 2
(2325 3650);
DISPLAY 1.234043 (2325 3650);
PAINT GREEN (2325 3650);
DISPLAY INVISIBLE (2325 3650);
FORCEPROP 1 LAST HDL_TAP TRUE
J 2
(2000 3575);
DISPLAY 1.234043 (2000 3575);
PAINT GREEN (2000 3575);
DISPLAY INVISIBLE (2000 3575);
FORCEPROP 1 LAST PATH I150
J 2
(2327 3700);
DISPLAY 0.872340 (2327 3700);
PAINT GREEN (2327 3700);
DISPLAY INVISIBLE (2327 3700);
FORCEADD TAP..6
R 2
(2525 3450);
FORCEPROP 3 LASTPIN (2475 3450) SIG_NAME M_B_DQS_DN<4>
J 0
(2485 3460);
DISPLAY 0.659574 (2485 3460);
PAINT MONO (2485 3460);
DISPLAY INVISIBLE (2485 3460);
FORCEPROP 1 LASTPIN (2475 3450) BN 4
J 2
(2525 3460);
DISPLAY 0.617021 (2525 3460);
PAINT PINK (2525 3460);
FORCEPROP 2 LAST CDS_LIB mstr_standard
J 0
(2525 3450);
DISPLAY 0.787234 (2525 3450);
PAINT MONO (2525 3450);
DISPLAY INVISIBLE (2525 3450);
FORCEPROP 1 LAST BODY_TYPE PLUMBING
J 2
(2525 3400);
DISPLAY 1.234043 (2525 3400);
PAINT GREEN (2525 3400);
DISPLAY INVISIBLE (2525 3400);
FORCEPROP 1 LAST HDL_TAP TRUE
J 2
(2200 3325);
DISPLAY 1.234043 (2200 3325);
PAINT GREEN (2200 3325);
DISPLAY INVISIBLE (2200 3325);
FORCEPROP 1 LAST PATH I151
J 2
(2527 3450);
DISPLAY 0.872340 (2527 3450);
PAINT GREEN (2527 3450);
DISPLAY INVISIBLE (2527 3450);
FORCEADD TAP..6
R 2
(2525 3350);
FORCEPROP 3 LASTPIN (2475 3350) SIG_NAME M_B_DQS_DN<3>
J 0
(2485 3360);
DISPLAY 0.659574 (2485 3360);
PAINT MONO (2485 3360);
DISPLAY INVISIBLE (2485 3360);
FORCEPROP 1 LASTPIN (2475 3350) BN 3
J 2
(2525 3360);
DISPLAY 0.617021 (2525 3360);
PAINT PINK (2525 3360);
FORCEPROP 2 LAST CDS_LIB mstr_standard
J 0
(2525 3350);
DISPLAY 0.787234 (2525 3350);
PAINT MONO (2525 3350);
DISPLAY INVISIBLE (2525 3350);
FORCEPROP 1 LAST BODY_TYPE PLUMBING
J 2
(2525 3300);
DISPLAY 1.234043 (2525 3300);
PAINT GREEN (2525 3300);
DISPLAY INVISIBLE (2525 3300);
FORCEPROP 1 LAST HDL_TAP TRUE
J 2
(2200 3225);
DISPLAY 1.234043 (2200 3225);
PAINT GREEN (2200 3225);
DISPLAY INVISIBLE (2200 3225);
FORCEPROP 1 LAST PATH I152
J 2
(2527 3350);
DISPLAY 0.872340 (2527 3350);
PAINT GREEN (2527 3350);
DISPLAY INVISIBLE (2527 3350);
FORCEADD TAP..6
R 2
(2525 3250);
FORCEPROP 3 LASTPIN (2475 3250) SIG_NAME M_B_DQS_DN<2>
J 0
(2485 3260);
DISPLAY 0.659574 (2485 3260);
PAINT MONO (2485 3260);
DISPLAY INVISIBLE (2485 3260);
FORCEPROP 1 LASTPIN (2475 3250) BN 2
J 2
(2525 3260);
DISPLAY 0.617021 (2525 3260);
PAINT PINK (2525 3260);
FORCEPROP 2 LAST CDS_LIB mstr_standard
J 0
(2525 3250);
DISPLAY 0.787234 (2525 3250);
PAINT MONO (2525 3250);
DISPLAY INVISIBLE (2525 3250);
FORCEPROP 1 LAST BODY_TYPE PLUMBING
J 2
(2525 3200);
DISPLAY 1.234043 (2525 3200);
PAINT GREEN (2525 3200);
DISPLAY INVISIBLE (2525 3200);
FORCEPROP 1 LAST HDL_TAP TRUE
J 2
(2200 3125);
DISPLAY 1.234043 (2200 3125);
PAINT GREEN (2200 3125);
DISPLAY INVISIBLE (2200 3125);
FORCEPROP 1 LAST PATH I153
J 2
(2527 3250);
DISPLAY 0.872340 (2527 3250);
PAINT GREEN (2527 3250);
DISPLAY INVISIBLE (2527 3250);
FORCEADD TAP..6
R 2
(2525 3550);
FORCEPROP 3 LASTPIN (2475 3550) SIG_NAME M_B_DQS_DN<5>
J 0
(2485 3560);
DISPLAY 0.659574 (2485 3560);
PAINT MONO (2485 3560);
DISPLAY INVISIBLE (2485 3560);
FORCEPROP 1 LASTPIN (2475 3550) BN 5
J 2
(2525 3560);
DISPLAY 0.617021 (2525 3560);
PAINT PINK (2525 3560);
FORCEPROP 2 LAST CDS_LIB mstr_standard
J 0
(2525 3550);
DISPLAY 0.787234 (2525 3550);
PAINT MONO (2525 3550);
DISPLAY INVISIBLE (2525 3550);
FORCEPROP 1 LAST BODY_TYPE PLUMBING
J 2
(2525 3500);
DISPLAY 1.234043 (2525 3500);
PAINT GREEN (2525 3500);
DISPLAY INVISIBLE (2525 3500);
FORCEPROP 1 LAST HDL_TAP TRUE
J 2
(2200 3425);
DISPLAY 1.234043 (2200 3425);
PAINT GREEN (2200 3425);
DISPLAY INVISIBLE (2200 3425);
FORCEPROP 1 LAST PATH I154
J 2
(2527 3550);
DISPLAY 0.872340 (2527 3550);
PAINT GREEN (2527 3550);
DISPLAY INVISIBLE (2527 3550);
FORCEADD TAP..6
R 2
(2525 3650);
FORCEPROP 3 LASTPIN (2475 3650) SIG_NAME M_B_DQS_DN<6>
J 0
(2485 3660);
DISPLAY 0.659574 (2485 3660);
PAINT MONO (2485 3660);
DISPLAY INVISIBLE (2485 3660);
FORCEPROP 1 LASTPIN (2475 3650) BN 6
J 2
(2525 3660);
DISPLAY 0.617021 (2525 3660);
PAINT PINK (2525 3660);
FORCEPROP 2 LAST CDS_LIB mstr_standard
J 0
(2525 3650);
DISPLAY 0.787234 (2525 3650);
PAINT MONO (2525 3650);
DISPLAY INVISIBLE (2525 3650);
FORCEPROP 1 LAST BODY_TYPE PLUMBING
J 2
(2525 3600);
DISPLAY 1.234043 (2525 3600);
PAINT GREEN (2525 3600);
DISPLAY INVISIBLE (2525 3600);
FORCEPROP 1 LAST HDL_TAP TRUE
J 2
(2200 3525);
DISPLAY 1.234043 (2200 3525);
PAINT GREEN (2200 3525);
DISPLAY INVISIBLE (2200 3525);
FORCEPROP 1 LAST PATH I155
J 2
(2527 3650);
DISPLAY 0.872340 (2527 3650);
PAINT GREEN (2527 3650);
DISPLAY INVISIBLE (2527 3650);
FORCEADD GND..1
R 2
(4125 950);
FORCEPROP 3 LASTPIN (4125 1000) SIG_NAME GND\g
J 0
(4135 1010);
DISPLAY 0.659574 (4135 1010);
PAINT MONO (4135 1010);
DISPLAY INVISIBLE (4135 1010);
FORCEPROP 1 LAST VOLTAGE 0
J 0
(4125 950);
PAINT SKYBLUE (4125 950);
DISPLAY INVISIBLE (4125 950);
FORCEPROP 1 LAST SIZE 1B
J 2
(4050 900);
DISPLAY 1.170213 (4050 900);
PAINT GREEN (4050 900);
DISPLAY INVISIBLE (4050 900);
FORCEPROP 2 LAST CDS_LIB mstr_symbols
J 0
(4125 950);
DISPLAY 0.787234 (4125 950);
PAINT MONO (4125 950);
DISPLAY INVISIBLE (4125 950);
FORCEPROP 2 LAST BOM_COST MEM
J 0
(4125 955);
PAINT ORANGE (4125 955);
DISPLAY INVISIBLE (4125 955);
FORCEPROP 1 LAST BODY_TYPE PLUMBING
J 2
(4170 907);
DISPLAY 0.340426 (4170 907);
PAINT GREEN (4170 907);
DISPLAY INVISIBLE (4170 907);
FORCEPROP 1 LAST PATH I156
J 2
(4050 950);
DISPLAY 0.872340 (4050 950);
PAINT AQUA (4050 950);
DISPLAY INVISIBLE (4050 950);
FORCEPROP 2 LAST ROOM DDR4_CH_A
J 0
(4125 955);
PAINT ORANGE (4125 955);
DISPLAY INVISIBLE (4125 955);
FORCEPROP 1 LAST HDL_POWER GND
J 2
(4125 1100);
DISPLAY 0.553191 (4125 1100);
PAINT GREEN (4125 1100);
DISPLAY INVISIBLE (4125 1100);
FORCEADD TAP..6
R 2
(2325 3800);
FORCEPROP 3 LASTPIN (2275 3800) SIG_NAME M_B_DQS_DP<7>
J 0
(2285 3810);
DISPLAY 0.659574 (2285 3810);
PAINT MONO (2285 3810);
DISPLAY INVISIBLE (2285 3810);
FORCEPROP 1 LASTPIN (2275 3800) BN 7
J 2
(2325 3810);
DISPLAY 0.617021 (2325 3810);
PAINT PINK (2325 3810);
FORCEPROP 2 LAST CDS_LIB mstr_standard
J 0
(2325 3800);
DISPLAY 0.787234 (2325 3800);
PAINT MONO (2325 3800);
DISPLAY INVISIBLE (2325 3800);
FORCEPROP 1 LAST BODY_TYPE PLUMBING
J 2
(2325 3750);
DISPLAY 1.234043 (2325 3750);
PAINT GREEN (2325 3750);
DISPLAY INVISIBLE (2325 3750);
FORCEPROP 1 LAST HDL_TAP TRUE
J 2
(2000 3675);
DISPLAY 1.234043 (2000 3675);
PAINT GREEN (2000 3675);
DISPLAY INVISIBLE (2000 3675);
FORCEPROP 1 LAST PATH I157
J 2
(2327 3800);
DISPLAY 0.872340 (2327 3800);
PAINT GREEN (2327 3800);
DISPLAY INVISIBLE (2327 3800);
FORCEADD TAP..6
R 2
(2325 4000);
FORCEPROP 3 LASTPIN (2275 4000) SIG_NAME M_B_DQS_DP<9>
J 0
(2285 4010);
DISPLAY 0.659574 (2285 4010);
PAINT MONO (2285 4010);
DISPLAY INVISIBLE (2285 4010);
FORCEPROP 1 LASTPIN (2275 4000) BN 9
J 2
(2325 4010);
DISPLAY 0.617021 (2325 4010);
PAINT PINK (2325 4010);
FORCEPROP 2 LAST CDS_LIB mstr_standard
J 0
(2325 4000);
DISPLAY 0.787234 (2325 4000);
PAINT MONO (2325 4000);
DISPLAY INVISIBLE (2325 4000);
FORCEPROP 1 LAST BODY_TYPE PLUMBING
J 2
(2325 3950);
DISPLAY 1.234043 (2325 3950);
PAINT GREEN (2325 3950);
DISPLAY INVISIBLE (2325 3950);
FORCEPROP 1 LAST HDL_TAP TRUE
J 2
(2000 3875);
DISPLAY 1.234043 (2000 3875);
PAINT GREEN (2000 3875);
DISPLAY INVISIBLE (2000 3875);
FORCEPROP 1 LAST PATH I158
J 2
(2327 4000);
DISPLAY 0.872340 (2327 4000);
PAINT GREEN (2327 4000);
DISPLAY INVISIBLE (2327 4000);
FORCEADD TAP..6
R 2
(2325 3900);
FORCEPROP 3 LASTPIN (2275 3900) SIG_NAME M_B_DQS_DP<8>
J 0
(2285 3910);
DISPLAY 0.659574 (2285 3910);
PAINT MONO (2285 3910);
DISPLAY INVISIBLE (2285 3910);
FORCEPROP 1 LASTPIN (2275 3900) BN 8
J 2
(2325 3910);
DISPLAY 0.617021 (2325 3910);
PAINT PINK (2325 3910);
FORCEPROP 2 LAST CDS_LIB mstr_standard
J 0
(2325 3900);
DISPLAY 0.787234 (2325 3900);
PAINT MONO (2325 3900);
DISPLAY INVISIBLE (2325 3900);
FORCEPROP 1 LAST BODY_TYPE PLUMBING
J 2
(2325 3850);
DISPLAY 1.234043 (2325 3850);
PAINT GREEN (2325 3850);
DISPLAY INVISIBLE (2325 3850);
FORCEPROP 1 LAST HDL_TAP TRUE
J 2
(2000 3775);
DISPLAY 1.234043 (2000 3775);
PAINT GREEN (2000 3775);
DISPLAY INVISIBLE (2000 3775);
FORCEPROP 1 LAST PATH I159
J 2
(2327 3900);
DISPLAY 0.872340 (2327 3900);
PAINT GREEN (2327 3900);
DISPLAY INVISIBLE (2327 3900);
FORCEADD OFFPAGE..1
(-2225 2200);
FORCEPROP 2 LAST $XR0 24 
J 0
(-2476 2200);
DISPLAY 0.638298 (-2476 2200);
PAINT MONO (-2476 2200);
FORCEPROP 2 LAST $XR1 45 
J 0
(-2566 2200);
DISPLAY 0.638298 (-2566 2200);
PAINT MONO (-2566 2200);
FORCEPROP 2 LAST CDS_LIB mstr_standard
J 0
(-2225 2200);
DISPLAY 0.787234 (-2225 2200);
PAINT MONO (-2225 2200);
DISPLAY INVISIBLE (-2225 2200);
FORCEPROP 1 LAST OFFPAGE TRUE
J 0
(-1900 2075);
DISPLAY 0.936170 (-1900 2075);
PAINT GREEN (-1900 2075);
DISPLAY INVISIBLE (-1900 2075);
FORCEPROP 1 LAST COMMENT_BODY TRUE
J 0
(-2100 2100);
DISPLAY 0.936170 (-2100 2100);
PAINT GREEN (-2100 2100);
DISPLAY INVISIBLE (-2100 2100);
FORCEPROP 2 LAST PATH I16
J 0
(-2425 2250);
DISPLAY 1.021277 (-2425 2250);
PAINT ORANGE (-2425 2250);
DISPLAY INVISIBLE (-2425 2250);
FORCEADD TAP..6
R 2
(2325 4100);
FORCEPROP 3 LASTPIN (2275 4100) SIG_NAME M_B_DQS_DP<10>
J 0
(2285 4110);
DISPLAY 0.659574 (2285 4110);
PAINT MONO (2285 4110);
DISPLAY INVISIBLE (2285 4110);
FORCEPROP 1 LASTPIN (2275 4100) BN 10
J 2
(2325 4110);
DISPLAY 0.617021 (2325 4110);
PAINT PINK (2325 4110);
FORCEPROP 2 LAST CDS_LIB mstr_standard
J 0
(2325 4100);
DISPLAY 0.787234 (2325 4100);
PAINT MONO (2325 4100);
DISPLAY INVISIBLE (2325 4100);
FORCEPROP 1 LAST BODY_TYPE PLUMBING
J 2
(2325 4050);
DISPLAY 1.234043 (2325 4050);
PAINT GREEN (2325 4050);
DISPLAY INVISIBLE (2325 4050);
FORCEPROP 1 LAST HDL_TAP TRUE
J 2
(2000 3975);
DISPLAY 1.234043 (2000 3975);
PAINT GREEN (2000 3975);
DISPLAY INVISIBLE (2000 3975);
FORCEPROP 1 LAST PATH I160
J 2
(2327 4100);
DISPLAY 0.872340 (2327 4100);
PAINT GREEN (2327 4100);
DISPLAY INVISIBLE (2327 4100);
FORCEADD TAP..6
R 2
(2325 4200);
FORCEPROP 3 LASTPIN (2275 4200) SIG_NAME M_B_DQS_DP<11>
J 0
(2285 4210);
DISPLAY 0.659574 (2285 4210);
PAINT MONO (2285 4210);
DISPLAY INVISIBLE (2285 4210);
FORCEPROP 1 LASTPIN (2275 4200) BN 11
J 2
(2325 4210);
DISPLAY 0.617021 (2325 4210);
PAINT PINK (2325 4210);
FORCEPROP 2 LAST CDS_LIB mstr_standard
J 0
(2325 4200);
DISPLAY 0.787234 (2325 4200);
PAINT MONO (2325 4200);
DISPLAY INVISIBLE (2325 4200);
FORCEPROP 1 LAST BODY_TYPE PLUMBING
J 2
(2325 4150);
DISPLAY 1.234043 (2325 4150);
PAINT GREEN (2325 4150);
DISPLAY INVISIBLE (2325 4150);
FORCEPROP 1 LAST HDL_TAP TRUE
J 2
(2000 4075);
DISPLAY 1.234043 (2000 4075);
PAINT GREEN (2000 4075);
DISPLAY INVISIBLE (2000 4075);
FORCEPROP 1 LAST PATH I161
J 2
(2327 4200);
DISPLAY 0.872340 (2327 4200);
PAINT GREEN (2327 4200);
DISPLAY INVISIBLE (2327 4200);
FORCEADD TAP..6
R 2
(2525 3950);
FORCEPROP 3 LASTPIN (2475 3950) SIG_NAME M_B_DQS_DN<9>
J 0
(2485 3960);
DISPLAY 0.659574 (2485 3960);
PAINT MONO (2485 3960);
DISPLAY INVISIBLE (2485 3960);
FORCEPROP 1 LASTPIN (2475 3950) BN 9
J 2
(2525 3960);
DISPLAY 0.617021 (2525 3960);
PAINT PINK (2525 3960);
FORCEPROP 2 LAST CDS_LIB mstr_standard
J 0
(2525 3950);
DISPLAY 0.787234 (2525 3950);
PAINT MONO (2525 3950);
DISPLAY INVISIBLE (2525 3950);
FORCEPROP 1 LAST BODY_TYPE PLUMBING
J 2
(2525 3900);
DISPLAY 1.234043 (2525 3900);
PAINT GREEN (2525 3900);
DISPLAY INVISIBLE (2525 3900);
FORCEPROP 1 LAST HDL_TAP TRUE
J 2
(2200 3825);
DISPLAY 1.234043 (2200 3825);
PAINT GREEN (2200 3825);
DISPLAY INVISIBLE (2200 3825);
FORCEPROP 1 LAST PATH I162
J 2
(2527 3950);
DISPLAY 0.872340 (2527 3950);
PAINT GREEN (2527 3950);
DISPLAY INVISIBLE (2527 3950);
FORCEADD TAP..6
R 2
(2525 3850);
FORCEPROP 3 LASTPIN (2475 3850) SIG_NAME M_B_DQS_DN<8>
J 0
(2485 3860);
DISPLAY 0.659574 (2485 3860);
PAINT MONO (2485 3860);
DISPLAY INVISIBLE (2485 3860);
FORCEPROP 1 LASTPIN (2475 3850) BN 8
J 2
(2525 3860);
DISPLAY 0.617021 (2525 3860);
PAINT PINK (2525 3860);
FORCEPROP 2 LAST CDS_LIB mstr_standard
J 0
(2525 3850);
DISPLAY 0.787234 (2525 3850);
PAINT MONO (2525 3850);
DISPLAY INVISIBLE (2525 3850);
FORCEPROP 1 LAST BODY_TYPE PLUMBING
J 2
(2525 3800);
DISPLAY 1.234043 (2525 3800);
PAINT GREEN (2525 3800);
DISPLAY INVISIBLE (2525 3800);
FORCEPROP 1 LAST HDL_TAP TRUE
J 2
(2200 3725);
DISPLAY 1.234043 (2200 3725);
PAINT GREEN (2200 3725);
DISPLAY INVISIBLE (2200 3725);
FORCEPROP 1 LAST PATH I163
J 2
(2527 3850);
DISPLAY 0.872340 (2527 3850);
PAINT GREEN (2527 3850);
DISPLAY INVISIBLE (2527 3850);
FORCEADD TAP..6
R 2
(2525 3750);
FORCEPROP 3 LASTPIN (2475 3750) SIG_NAME M_B_DQS_DN<7>
J 0
(2485 3760);
DISPLAY 0.659574 (2485 3760);
PAINT MONO (2485 3760);
DISPLAY INVISIBLE (2485 3760);
FORCEPROP 1 LASTPIN (2475 3750) BN 7
J 2
(2525 3760);
DISPLAY 0.617021 (2525 3760);
PAINT PINK (2525 3760);
FORCEPROP 2 LAST CDS_LIB mstr_standard
J 0
(2525 3750);
DISPLAY 0.787234 (2525 3750);
PAINT MONO (2525 3750);
DISPLAY INVISIBLE (2525 3750);
FORCEPROP 1 LAST BODY_TYPE PLUMBING
J 2
(2525 3700);
DISPLAY 1.234043 (2525 3700);
PAINT GREEN (2525 3700);
DISPLAY INVISIBLE (2525 3700);
FORCEPROP 1 LAST HDL_TAP TRUE
J 2
(2200 3625);
DISPLAY 1.234043 (2200 3625);
PAINT GREEN (2200 3625);
DISPLAY INVISIBLE (2200 3625);
FORCEPROP 1 LAST PATH I164
J 2
(2527 3750);
DISPLAY 0.872340 (2527 3750);
PAINT GREEN (2527 3750);
DISPLAY INVISIBLE (2527 3750);
FORCEADD TAP..6
R 2
(2525 4250);
FORCEPROP 3 LASTPIN (2475 4250) SIG_NAME M_B_DQS_DN<12>
J 0
(2485 4260);
DISPLAY 0.659574 (2485 4260);
PAINT MONO (2485 4260);
DISPLAY INVISIBLE (2485 4260);
FORCEPROP 1 LASTPIN (2475 4250) BN 12
J 2
(2525 4260);
DISPLAY 0.617021 (2525 4260);
PAINT PINK (2525 4260);
FORCEPROP 2 LAST CDS_LIB mstr_standard
J 0
(2525 4250);
DISPLAY 0.787234 (2525 4250);
PAINT MONO (2525 4250);
DISPLAY INVISIBLE (2525 4250);
FORCEPROP 1 LAST BODY_TYPE PLUMBING
J 2
(2525 4200);
DISPLAY 1.234043 (2525 4200);
PAINT GREEN (2525 4200);
DISPLAY INVISIBLE (2525 4200);
FORCEPROP 1 LAST HDL_TAP TRUE
J 2
(2200 4125);
DISPLAY 1.234043 (2200 4125);
PAINT GREEN (2200 4125);
DISPLAY INVISIBLE (2200 4125);
FORCEPROP 1 LAST PATH I165
J 2
(2527 4250);
DISPLAY 0.872340 (2527 4250);
PAINT GREEN (2527 4250);
DISPLAY INVISIBLE (2527 4250);
FORCEADD TAP..6
R 2
(2525 4050);
FORCEPROP 3 LASTPIN (2475 4050) SIG_NAME M_B_DQS_DN<10>
J 0
(2485 4060);
DISPLAY 0.659574 (2485 4060);
PAINT MONO (2485 4060);
DISPLAY INVISIBLE (2485 4060);
FORCEPROP 1 LASTPIN (2475 4050) BN 10
J 2
(2525 4060);
DISPLAY 0.617021 (2525 4060);
PAINT PINK (2525 4060);
FORCEPROP 2 LAST CDS_LIB mstr_standard
J 0
(2525 4050);
DISPLAY 0.787234 (2525 4050);
PAINT MONO (2525 4050);
DISPLAY INVISIBLE (2525 4050);
FORCEPROP 1 LAST BODY_TYPE PLUMBING
J 2
(2525 4000);
DISPLAY 1.234043 (2525 4000);
PAINT GREEN (2525 4000);
DISPLAY INVISIBLE (2525 4000);
FORCEPROP 1 LAST HDL_TAP TRUE
J 2
(2200 3925);
DISPLAY 1.234043 (2200 3925);
PAINT GREEN (2200 3925);
DISPLAY INVISIBLE (2200 3925);
FORCEPROP 1 LAST PATH I166
J 2
(2527 4050);
DISPLAY 0.872340 (2527 4050);
PAINT GREEN (2527 4050);
DISPLAY INVISIBLE (2527 4050);
FORCEADD TAP..6
R 2
(2525 4150);
FORCEPROP 3 LASTPIN (2475 4150) SIG_NAME M_B_DQS_DN<11>
J 0
(2485 4160);
DISPLAY 0.659574 (2485 4160);
PAINT MONO (2485 4160);
DISPLAY INVISIBLE (2485 4160);
FORCEPROP 1 LASTPIN (2475 4150) BN 11
J 2
(2525 4160);
DISPLAY 0.617021 (2525 4160);
PAINT PINK (2525 4160);
FORCEPROP 2 LAST CDS_LIB mstr_standard
J 0
(2525 4150);
DISPLAY 0.787234 (2525 4150);
PAINT MONO (2525 4150);
DISPLAY INVISIBLE (2525 4150);
FORCEPROP 1 LAST BODY_TYPE PLUMBING
J 2
(2525 4100);
DISPLAY 1.234043 (2525 4100);
PAINT GREEN (2525 4100);
DISPLAY INVISIBLE (2525 4100);
FORCEPROP 1 LAST HDL_TAP TRUE
J 2
(2200 4025);
DISPLAY 1.234043 (2200 4025);
PAINT GREEN (2200 4025);
DISPLAY INVISIBLE (2200 4025);
FORCEPROP 1 LAST PATH I167
J 2
(2527 4150);
DISPLAY 0.872340 (2527 4150);
PAINT GREEN (2527 4150);
DISPLAY INVISIBLE (2527 4150);
FORCEADD TAP..6
R 2
(2325 4300);
FORCEPROP 3 LASTPIN (2275 4300) SIG_NAME M_B_DQS_DP<12>
J 0
(2285 4310);
DISPLAY 0.659574 (2285 4310);
PAINT MONO (2285 4310);
DISPLAY INVISIBLE (2285 4310);
FORCEPROP 1 LASTPIN (2275 4300) BN 12
J 2
(2325 4310);
DISPLAY 0.617021 (2325 4310);
PAINT PINK (2325 4310);
FORCEPROP 2 LAST CDS_LIB mstr_standard
J 0
(2325 4300);
DISPLAY 0.787234 (2325 4300);
PAINT MONO (2325 4300);
DISPLAY INVISIBLE (2325 4300);
FORCEPROP 1 LAST BODY_TYPE PLUMBING
J 2
(2325 4250);
DISPLAY 1.234043 (2325 4250);
PAINT GREEN (2325 4250);
DISPLAY INVISIBLE (2325 4250);
FORCEPROP 1 LAST HDL_TAP TRUE
J 2
(2000 4175);
DISPLAY 1.234043 (2000 4175);
PAINT GREEN (2000 4175);
DISPLAY INVISIBLE (2000 4175);
FORCEPROP 1 LAST PATH I168
J 2
(2327 4300);
DISPLAY 0.872340 (2327 4300);
PAINT GREEN (2327 4300);
DISPLAY INVISIBLE (2327 4300);
FORCEADD TAP..6
R 2
(2325 4500);
FORCEPROP 3 LASTPIN (2275 4500) SIG_NAME M_B_DQS_DP<14>
J 0
(2285 4510);
DISPLAY 0.659574 (2285 4510);
PAINT MONO (2285 4510);
DISPLAY INVISIBLE (2285 4510);
FORCEPROP 1 LASTPIN (2275 4500) BN 14
J 2
(2325 4510);
DISPLAY 0.617021 (2325 4510);
PAINT PINK (2325 4510);
FORCEPROP 2 LAST CDS_LIB mstr_standard
J 0
(2325 4500);
DISPLAY 0.787234 (2325 4500);
PAINT MONO (2325 4500);
DISPLAY INVISIBLE (2325 4500);
FORCEPROP 1 LAST BODY_TYPE PLUMBING
J 2
(2325 4450);
DISPLAY 1.234043 (2325 4450);
PAINT GREEN (2325 4450);
DISPLAY INVISIBLE (2325 4450);
FORCEPROP 1 LAST HDL_TAP TRUE
J 2
(2000 4375);
DISPLAY 1.234043 (2000 4375);
PAINT GREEN (2000 4375);
DISPLAY INVISIBLE (2000 4375);
FORCEPROP 1 LAST PATH I169
J 2
(2327 4500);
DISPLAY 0.872340 (2327 4500);
PAINT GREEN (2327 4500);
DISPLAY INVISIBLE (2327 4500);
FORCEADD OFFPAGE..6
(-2225 2250);
FORCEPROP 2 LAST $XR0 24 
J 0
(-2474 2250);
DISPLAY 0.638298 (-2474 2250);
PAINT MONO (-2474 2250);
FORCEPROP 2 LAST $XR1 45 
J 0
(-2564 2250);
DISPLAY 0.638298 (-2564 2250);
PAINT MONO (-2564 2250);
FORCEPROP 2 LAST CDS_LIB mstr_standard
J 0
(-2225 2250);
DISPLAY 0.787234 (-2225 2250);
PAINT MONO (-2225 2250);
DISPLAY INVISIBLE (-2225 2250);
FORCEPROP 1 LAST OFFPAGE TRUE
J 0
(-1900 2125);
DISPLAY 0.936170 (-1900 2125);
PAINT GREEN (-1900 2125);
DISPLAY INVISIBLE (-1900 2125);
FORCEPROP 1 LAST COMMENT_BODY TRUE
J 0
(-2125 2175);
DISPLAY 0.936170 (-2125 2175);
PAINT GREEN (-2125 2175);
DISPLAY INVISIBLE (-2125 2175);
FORCEPROP 2 LAST PATH I17
J 0
(-2425 2300);
DISPLAY 1.021277 (-2425 2300);
PAINT ORANGE (-2425 2300);
DISPLAY INVISIBLE (-2425 2300);
FORCEADD TAP..6
R 2
(2325 4400);
FORCEPROP 3 LASTPIN (2275 4400) SIG_NAME M_B_DQS_DP<13>
J 0
(2285 4410);
DISPLAY 0.659574 (2285 4410);
PAINT MONO (2285 4410);
DISPLAY INVISIBLE (2285 4410);
FORCEPROP 1 LASTPIN (2275 4400) BN 13
J 2
(2325 4410);
DISPLAY 0.617021 (2325 4410);
PAINT PINK (2325 4410);
FORCEPROP 2 LAST CDS_LIB mstr_standard
J 0
(2325 4400);
DISPLAY 0.787234 (2325 4400);
PAINT MONO (2325 4400);
DISPLAY INVISIBLE (2325 4400);
FORCEPROP 1 LAST BODY_TYPE PLUMBING
J 2
(2325 4350);
DISPLAY 1.234043 (2325 4350);
PAINT GREEN (2325 4350);
DISPLAY INVISIBLE (2325 4350);
FORCEPROP 1 LAST HDL_TAP TRUE
J 2
(2000 4275);
DISPLAY 1.234043 (2000 4275);
PAINT GREEN (2000 4275);
DISPLAY INVISIBLE (2000 4275);
FORCEPROP 1 LAST PATH I170
J 2
(2327 4400);
DISPLAY 0.872340 (2327 4400);
PAINT GREEN (2327 4400);
DISPLAY INVISIBLE (2327 4400);
FORCEADD TAP..6
R 2
(2325 4600);
FORCEPROP 3 LASTPIN (2275 4600) SIG_NAME M_B_DQS_DP<15>
J 0
(2285 4610);
DISPLAY 0.659574 (2285 4610);
PAINT MONO (2285 4610);
DISPLAY INVISIBLE (2285 4610);
FORCEPROP 1 LASTPIN (2275 4600) BN 15
J 2
(2325 4610);
DISPLAY 0.617021 (2325 4610);
PAINT PINK (2325 4610);
FORCEPROP 2 LAST CDS_LIB mstr_standard
J 0
(2325 4600);
DISPLAY 0.787234 (2325 4600);
PAINT MONO (2325 4600);
DISPLAY INVISIBLE (2325 4600);
FORCEPROP 1 LAST BODY_TYPE PLUMBING
J 2
(2325 4550);
DISPLAY 1.234043 (2325 4550);
PAINT GREEN (2325 4550);
DISPLAY INVISIBLE (2325 4550);
FORCEPROP 1 LAST HDL_TAP TRUE
J 2
(2000 4475);
DISPLAY 1.234043 (2000 4475);
PAINT GREEN (2000 4475);
DISPLAY INVISIBLE (2000 4475);
FORCEPROP 1 LAST PATH I171
J 2
(2327 4600);
DISPLAY 0.872340 (2327 4600);
PAINT GREEN (2327 4600);
DISPLAY INVISIBLE (2327 4600);
FORCEADD TAP..6
R 2
(2325 4700);
FORCEPROP 3 LASTPIN (2275 4700) SIG_NAME M_B_DQS_DP<16>
J 0
(2285 4710);
DISPLAY 0.659574 (2285 4710);
PAINT MONO (2285 4710);
DISPLAY INVISIBLE (2285 4710);
FORCEPROP 1 LASTPIN (2275 4700) BN 16
J 2
(2325 4710);
DISPLAY 0.617021 (2325 4710);
PAINT PINK (2325 4710);
FORCEPROP 2 LAST CDS_LIB mstr_standard
J 0
(2325 4700);
DISPLAY 0.787234 (2325 4700);
PAINT MONO (2325 4700);
DISPLAY INVISIBLE (2325 4700);
FORCEPROP 1 LAST BODY_TYPE PLUMBING
J 2
(2325 4650);
DISPLAY 1.234043 (2325 4650);
PAINT GREEN (2325 4650);
DISPLAY INVISIBLE (2325 4650);
FORCEPROP 1 LAST HDL_TAP TRUE
J 2
(2000 4575);
DISPLAY 1.234043 (2000 4575);
PAINT GREEN (2000 4575);
DISPLAY INVISIBLE (2000 4575);
FORCEPROP 1 LAST PATH I172
J 2
(2327 4700);
DISPLAY 0.872340 (2327 4700);
PAINT GREEN (2327 4700);
DISPLAY INVISIBLE (2327 4700);
FORCEADD TAP..6
R 2
(2525 4350);
FORCEPROP 3 LASTPIN (2475 4350) SIG_NAME M_B_DQS_DN<13>
J 0
(2485 4360);
DISPLAY 0.659574 (2485 4360);
PAINT MONO (2485 4360);
DISPLAY INVISIBLE (2485 4360);
FORCEPROP 1 LASTPIN (2475 4350) BN 13
J 2
(2525 4360);
DISPLAY 0.617021 (2525 4360);
PAINT PINK (2525 4360);
FORCEPROP 2 LAST CDS_LIB mstr_standard
J 0
(2525 4350);
DISPLAY 0.787234 (2525 4350);
PAINT MONO (2525 4350);
DISPLAY INVISIBLE (2525 4350);
FORCEPROP 1 LAST BODY_TYPE PLUMBING
J 2
(2525 4300);
DISPLAY 1.234043 (2525 4300);
PAINT GREEN (2525 4300);
DISPLAY INVISIBLE (2525 4300);
FORCEPROP 1 LAST HDL_TAP TRUE
J 2
(2200 4225);
DISPLAY 1.234043 (2200 4225);
PAINT GREEN (2200 4225);
DISPLAY INVISIBLE (2200 4225);
FORCEPROP 1 LAST PATH I173
J 2
(2527 4350);
DISPLAY 0.872340 (2527 4350);
PAINT GREEN (2527 4350);
DISPLAY INVISIBLE (2527 4350);
FORCEADD TAP..6
R 2
(2525 4450);
FORCEPROP 3 LASTPIN (2475 4450) SIG_NAME M_B_DQS_DN<14>
J 0
(2485 4460);
DISPLAY 0.659574 (2485 4460);
PAINT MONO (2485 4460);
DISPLAY INVISIBLE (2485 4460);
FORCEPROP 1 LASTPIN (2475 4450) BN 14
J 2
(2525 4460);
DISPLAY 0.617021 (2525 4460);
PAINT PINK (2525 4460);
FORCEPROP 2 LAST CDS_LIB mstr_standard
J 0
(2525 4450);
DISPLAY 0.787234 (2525 4450);
PAINT MONO (2525 4450);
DISPLAY INVISIBLE (2525 4450);
FORCEPROP 1 LAST BODY_TYPE PLUMBING
J 2
(2525 4400);
DISPLAY 1.234043 (2525 4400);
PAINT GREEN (2525 4400);
DISPLAY INVISIBLE (2525 4400);
FORCEPROP 1 LAST HDL_TAP TRUE
J 2
(2200 4325);
DISPLAY 1.234043 (2200 4325);
PAINT GREEN (2200 4325);
DISPLAY INVISIBLE (2200 4325);
FORCEPROP 1 LAST PATH I174
J 2
(2527 4450);
DISPLAY 0.872340 (2527 4450);
PAINT GREEN (2527 4450);
DISPLAY INVISIBLE (2527 4450);
FORCEADD TAP..6
R 2
(2525 4750);
FORCEPROP 3 LASTPIN (2475 4750) SIG_NAME M_B_DQS_DN<17>
J 0
(2485 4760);
DISPLAY 0.659574 (2485 4760);
PAINT MONO (2485 4760);
DISPLAY INVISIBLE (2485 4760);
FORCEPROP 1 LASTPIN (2475 4750) BN 17
J 2
(2525 4760);
DISPLAY 0.617021 (2525 4760);
PAINT PINK (2525 4760);
FORCEPROP 2 LAST CDS_LIB mstr_standard
J 2
(2525 4750);
DISPLAY 0.787234 (2525 4750);
PAINT MONO (2525 4750);
DISPLAY INVISIBLE (2525 4750);
FORCEPROP 1 LAST BODY_TYPE PLUMBING
J 2
(2525 4700);
DISPLAY 1.234043 (2525 4700);
PAINT GREEN (2525 4700);
DISPLAY INVISIBLE (2525 4700);
FORCEPROP 1 LAST HDL_TAP TRUE
J 2
(2200 4625);
DISPLAY 1.234043 (2200 4625);
PAINT GREEN (2200 4625);
DISPLAY INVISIBLE (2200 4625);
FORCEPROP 1 LAST PATH I175
J 2
(2527 4750);
DISPLAY 0.872340 (2527 4750);
PAINT GREEN (2527 4750);
DISPLAY INVISIBLE (2527 4750);
FORCEADD TAP..6
R 2
(2525 4550);
FORCEPROP 3 LASTPIN (2475 4550) SIG_NAME M_B_DQS_DN<15>
J 0
(2485 4560);
DISPLAY 0.659574 (2485 4560);
PAINT MONO (2485 4560);
DISPLAY INVISIBLE (2485 4560);
FORCEPROP 1 LASTPIN (2475 4550) BN 15
J 2
(2525 4560);
DISPLAY 0.617021 (2525 4560);
PAINT PINK (2525 4560);
FORCEPROP 2 LAST CDS_LIB mstr_standard
J 0
(2525 4550);
DISPLAY 0.787234 (2525 4550);
PAINT MONO (2525 4550);
DISPLAY INVISIBLE (2525 4550);
FORCEPROP 1 LAST BODY_TYPE PLUMBING
J 2
(2525 4500);
DISPLAY 1.234043 (2525 4500);
PAINT GREEN (2525 4500);
DISPLAY INVISIBLE (2525 4500);
FORCEPROP 1 LAST HDL_TAP TRUE
J 2
(2200 4425);
DISPLAY 1.234043 (2200 4425);
PAINT GREEN (2200 4425);
DISPLAY INVISIBLE (2200 4425);
FORCEPROP 1 LAST PATH I176
J 2
(2527 4550);
DISPLAY 0.872340 (2527 4550);
PAINT GREEN (2527 4550);
DISPLAY INVISIBLE (2527 4550);
FORCEADD TAP..6
R 2
(2525 4650);
FORCEPROP 3 LASTPIN (2475 4650) SIG_NAME M_B_DQS_DN<16>
J 0
(2485 4660);
DISPLAY 0.659574 (2485 4660);
PAINT MONO (2485 4660);
DISPLAY INVISIBLE (2485 4660);
FORCEPROP 1 LASTPIN (2475 4650) BN 16
J 2
(2525 4660);
DISPLAY 0.617021 (2525 4660);
PAINT PINK (2525 4660);
FORCEPROP 2 LAST CDS_LIB mstr_standard
J 0
(2525 4650);
DISPLAY 0.787234 (2525 4650);
PAINT MONO (2525 4650);
DISPLAY INVISIBLE (2525 4650);
FORCEPROP 1 LAST BODY_TYPE PLUMBING
J 2
(2525 4600);
DISPLAY 1.234043 (2525 4600);
PAINT GREEN (2525 4600);
DISPLAY INVISIBLE (2525 4600);
FORCEPROP 1 LAST HDL_TAP TRUE
J 2
(2200 4525);
DISPLAY 1.234043 (2200 4525);
PAINT GREEN (2200 4525);
DISPLAY INVISIBLE (2200 4525);
FORCEPROP 1 LAST PATH I177
J 2
(2527 4650);
DISPLAY 0.872340 (2527 4650);
PAINT GREEN (2527 4650);
DISPLAY INVISIBLE (2527 4650);
FORCEADD TAP..6
R 2
(2325 4800);
FORCEPROP 3 LASTPIN (2275 4800) SIG_NAME M_B_DQS_DP<17>
J 0
(2285 4810);
DISPLAY 0.659574 (2285 4810);
PAINT MONO (2285 4810);
DISPLAY INVISIBLE (2285 4810);
FORCEPROP 1 LASTPIN (2275 4800) BN 17
J 2
(2325 4810);
DISPLAY 0.617021 (2325 4810);
PAINT PINK (2325 4810);
FORCEPROP 2 LAST CDS_LIB mstr_standard
J 2
(2325 4800);
DISPLAY 0.787234 (2325 4800);
PAINT MONO (2325 4800);
DISPLAY INVISIBLE (2325 4800);
FORCEPROP 1 LAST BODY_TYPE PLUMBING
J 2
(2325 4750);
DISPLAY 1.234043 (2325 4750);
PAINT GREEN (2325 4750);
DISPLAY INVISIBLE (2325 4750);
FORCEPROP 1 LAST HDL_TAP TRUE
J 2
(2000 4675);
DISPLAY 1.234043 (2000 4675);
PAINT GREEN (2000 4675);
DISPLAY INVISIBLE (2000 4675);
FORCEPROP 1 LAST PATH I178
J 2
(2327 4800);
DISPLAY 0.872340 (2327 4800);
PAINT GREEN (2327 4800);
DISPLAY INVISIBLE (2327 4800);
FORCEADD OFFPAGE..3
(3225 4800);
FORCEPROP 2 LAST $XR0 24 
J 0
(3439 4800);
DISPLAY 0.638298 (3439 4800);
PAINT MONO (3439 4800);
FORCEPROP 2 LAST $XR1 45 
J 0
(3529 4800);
DISPLAY 0.638298 (3529 4800);
PAINT MONO (3529 4800);
FORCEPROP 2 LAST CDS_LIB mstr_standard
J 0
(3225 4800);
DISPLAY 0.787234 (3225 4800);
PAINT MONO (3225 4800);
DISPLAY INVISIBLE (3225 4800);
FORCEPROP 1 LAST OFFPAGE TRUE
J 0
(3550 4675);
DISPLAY 0.936170 (3550 4675);
PAINT GREEN (3550 4675);
DISPLAY INVISIBLE (3550 4675);
FORCEPROP 1 LAST COMMENT_BODY TRUE
J 0
(3175 4700);
DISPLAY 0.936170 (3175 4700);
PAINT GREEN (3175 4700);
DISPLAY INVISIBLE (3175 4700);
FORCEPROP 2 LAST PATH I179
J 0
(3450 4850);
DISPLAY 1.021277 (3450 4850);
PAINT ORANGE (3450 4850);
DISPLAY INVISIBLE (3450 4850);
FORCEADD OFFPAGE..1
(-2225 2450);
FORCEPROP 2 LAST $XR0 24 
J 0
(-2476 2450);
DISPLAY 0.638298 (-2476 2450);
PAINT MONO (-2476 2450);
FORCEPROP 2 LAST $XR1 45 
J 0
(-2566 2450);
DISPLAY 0.638298 (-2566 2450);
PAINT MONO (-2566 2450);
FORCEPROP 2 LAST CDS_LIB mstr_standard
J 0
(-2225 2450);
DISPLAY 0.787234 (-2225 2450);
PAINT MONO (-2225 2450);
DISPLAY INVISIBLE (-2225 2450);
FORCEPROP 1 LAST OFFPAGE TRUE
J 0
(-1900 2325);
DISPLAY 0.936170 (-1900 2325);
PAINT GREEN (-1900 2325);
DISPLAY INVISIBLE (-1900 2325);
FORCEPROP 1 LAST COMMENT_BODY TRUE
J 0
(-2100 2350);
DISPLAY 0.936170 (-2100 2350);
PAINT GREEN (-2100 2350);
DISPLAY INVISIBLE (-2100 2350);
FORCEPROP 2 LAST PATH I18
J 0
(-2425 2500);
DISPLAY 1.021277 (-2425 2500);
PAINT ORANGE (-2425 2500);
DISPLAY INVISIBLE (-2425 2500);
FORCEADD OFFPAGE..3
(3225 4850);
FORCEPROP 2 LAST $XR0 24 
J 0
(3439 4850);
DISPLAY 0.638298 (3439 4850);
PAINT MONO (3439 4850);
FORCEPROP 2 LAST $XR1 45 
J 0
(3529 4850);
DISPLAY 0.638298 (3529 4850);
PAINT MONO (3529 4850);
FORCEPROP 2 LAST CDS_LIB mstr_standard
J 0
(3225 4850);
DISPLAY 0.787234 (3225 4850);
PAINT MONO (3225 4850);
DISPLAY INVISIBLE (3225 4850);
FORCEPROP 1 LAST OFFPAGE TRUE
J 0
(3550 4725);
DISPLAY 0.936170 (3550 4725);
PAINT GREEN (3550 4725);
DISPLAY INVISIBLE (3550 4725);
FORCEPROP 1 LAST COMMENT_BODY TRUE
J 0
(3175 4750);
DISPLAY 0.936170 (3175 4750);
PAINT GREEN (3175 4750);
DISPLAY INVISIBLE (3175 4750);
FORCEPROP 2 LAST PATH I180
J 0
(3450 4900);
DISPLAY 1.021277 (3450 4900);
PAINT ORANGE (3450 4900);
DISPLAY INVISIBLE (3450 4900);
FORCEADD P12V_NVDIMM_ABC..1
(2375 2725);
FORCEPROP 3 LASTPIN (2375 2675) SIG_NAME P12V_NVDIMM_ABC\g
J 0
(2385 2685);
DISPLAY 0.659574 (2385 2685);
PAINT MONO (2385 2685);
DISPLAY INVISIBLE (2385 2685);
FORCEPROP 1 LAST VOLTAGE 12.0
J 0
(2330 2682);
DISPLAY 0.340426 (2330 2682);
PAINT SKYBLUE (2330 2682);
DISPLAY INVISIBLE (2330 2682);
FORCEPROP 2 LAST CDS_LIB mstr_symbols
J 0
(2375 2725);
PAINT ORANGE (2375 2725);
DISPLAY INVISIBLE (2375 2725);
FORCEPROP 1 LAST BODY_TYPE PLUMBING
J 0
(2330 2682);
DISPLAY 0.340426 (2330 2682);
PAINT GREEN (2330 2682);
DISPLAY INVISIBLE (2330 2682);
FORCEPROP 1 LAST PATH I181
J 0
(2425 2750);
DISPLAY 0.872340 (2425 2750);
PAINT AQUA (2425 2750);
DISPLAY INVISIBLE (2425 2750);
FORCEPROP 1 LAST HDL_POWER P12V_NVDIMM_ABC
J 1
(2375 2750);
DISPLAY 0.872340 (2375 2750);
PAINT GREEN (2375 2750);
DISPLAY INVISIBLE (2375 2750);
FORCEADD OFFPAGE..1
(-2225 2600);
FORCEPROP 2 LAST $XR0 24 
J 0
(-2476 2600);
DISPLAY 0.638298 (-2476 2600);
PAINT MONO (-2476 2600);
FORCEPROP 2 LAST $XR1 45 
J 0
(-2566 2600);
DISPLAY 0.638298 (-2566 2600);
PAINT MONO (-2566 2600);
FORCEPROP 2 LAST CDS_LIB mstr_standard
J 0
(-2225 2600);
DISPLAY 0.787234 (-2225 2600);
PAINT MONO (-2225 2600);
DISPLAY INVISIBLE (-2225 2600);
FORCEPROP 1 LAST OFFPAGE TRUE
J 0
(-1900 2475);
DISPLAY 0.936170 (-1900 2475);
PAINT GREEN (-1900 2475);
DISPLAY INVISIBLE (-1900 2475);
FORCEPROP 1 LAST COMMENT_BODY TRUE
J 0
(-2100 2500);
DISPLAY 0.936170 (-2100 2500);
PAINT GREEN (-2100 2500);
DISPLAY INVISIBLE (-2100 2500);
FORCEPROP 2 LAST PATH I19
J 0
(-2425 2650);
DISPLAY 1.021277 (-2425 2650);
PAINT ORANGE (-2425 2650);
DISPLAY INVISIBLE (-2425 2650);
FORCEADD OFFPAGE..1
(-3125 1100);
FORCEPROP 2 LAST $XR0 98 
J 0
(-3346 1100);
DISPLAY 0.638298 (-3346 1100);
PAINT MONO (-3346 1100);
FORCEPROP 2 LAST $XR1 45 
J 0
(-3436 1100);
DISPLAY 0.638298 (-3436 1100);
PAINT MONO (-3436 1100);
FORCEPROP 2 LAST CDS_LIB mstr_standard
J 0
(-3125 1100);
DISPLAY 0.787234 (-3125 1100);
PAINT MONO (-3125 1100);
DISPLAY INVISIBLE (-3125 1100);
FORCEPROP 1 LAST OFFPAGE TRUE
J 0
(-2800 975);
DISPLAY 0.936170 (-2800 975);
PAINT GREEN (-2800 975);
DISPLAY INVISIBLE (-2800 975);
FORCEPROP 1 LAST COMMENT_BODY TRUE
J 0
(-3000 1000);
DISPLAY 0.936170 (-3000 1000);
PAINT GREEN (-3000 1000);
DISPLAY INVISIBLE (-3000 1000);
FORCEPROP 2 LAST PATH I2
J 0
(-3325 1150);
DISPLAY 1.021277 (-3325 1150);
PAINT ORANGE (-3325 1150);
DISPLAY INVISIBLE (-3325 1150);
FORCEADD TAP..6
(-1575 1900);
FORCEPROP 3 LASTPIN (-1525 1900) SIG_NAME M_B_ECC<1>
J 0
(-1515 1910);
DISPLAY 0.659574 (-1515 1910);
PAINT MONO (-1515 1910);
DISPLAY INVISIBLE (-1515 1910);
FORCEPROP 1 LASTPIN (-1525 1900) BN 1
J 0
(-1575 1910);
DISPLAY 0.617021 (-1575 1910);
PAINT PINK (-1575 1910);
FORCEPROP 2 LAST CDS_LIB mstr_standard
J 0
(-1575 1900);
DISPLAY 0.787234 (-1575 1900);
PAINT MONO (-1575 1900);
DISPLAY INVISIBLE (-1575 1900);
FORCEPROP 1 LAST BODY_TYPE PLUMBING
J 0
(-1575 1850);
DISPLAY 1.234043 (-1575 1850);
PAINT GREEN (-1575 1850);
DISPLAY INVISIBLE (-1575 1850);
FORCEPROP 1 LAST HDL_TAP TRUE
J 0
(-1250 1775);
DISPLAY 1.234043 (-1250 1775);
PAINT GREEN (-1250 1775);
DISPLAY INVISIBLE (-1250 1775);
FORCEPROP 1 LAST PATH I20
J 0
(-1577 1900);
DISPLAY 0.872340 (-1577 1900);
PAINT GREEN (-1577 1900);
DISPLAY INVISIBLE (-1577 1900);
FORCEADD TAP..6
(-1575 1850);
FORCEPROP 3 LASTPIN (-1525 1850) SIG_NAME M_B_ECC<0>
J 0
(-1515 1860);
DISPLAY 0.659574 (-1515 1860);
PAINT MONO (-1515 1860);
DISPLAY INVISIBLE (-1515 1860);
FORCEPROP 1 LASTPIN (-1525 1850) BN 0
J 0
(-1575 1860);
DISPLAY 0.617021 (-1575 1860);
PAINT PINK (-1575 1860);
FORCEPROP 2 LAST CDS_LIB mstr_standard
J 0
(-1575 1850);
DISPLAY 0.787234 (-1575 1850);
PAINT MONO (-1575 1850);
DISPLAY INVISIBLE (-1575 1850);
FORCEPROP 1 LAST BODY_TYPE PLUMBING
J 0
(-1575 1800);
DISPLAY 1.234043 (-1575 1800);
PAINT GREEN (-1575 1800);
DISPLAY INVISIBLE (-1575 1800);
FORCEPROP 1 LAST HDL_TAP TRUE
J 0
(-1250 1725);
DISPLAY 1.234043 (-1250 1725);
PAINT GREEN (-1250 1725);
DISPLAY INVISIBLE (-1250 1725);
FORCEPROP 1 LAST PATH I21
J 0
(-1577 1850);
DISPLAY 0.872340 (-1577 1850);
PAINT GREEN (-1577 1850);
DISPLAY INVISIBLE (-1577 1850);
FORCEADD TAP..6
(-1575 1950);
FORCEPROP 3 LASTPIN (-1525 1950) SIG_NAME M_B_ECC<2>
J 0
(-1515 1960);
DISPLAY 0.659574 (-1515 1960);
PAINT MONO (-1515 1960);
DISPLAY INVISIBLE (-1515 1960);
FORCEPROP 1 LASTPIN (-1525 1950) BN 2
J 0
(-1575 1960);
DISPLAY 0.617021 (-1575 1960);
PAINT PINK (-1575 1960);
FORCEPROP 2 LAST CDS_LIB mstr_standard
J 0
(-1575 1950);
DISPLAY 0.787234 (-1575 1950);
PAINT MONO (-1575 1950);
DISPLAY INVISIBLE (-1575 1950);
FORCEPROP 1 LAST BODY_TYPE PLUMBING
J 0
(-1575 1900);
DISPLAY 1.234043 (-1575 1900);
PAINT GREEN (-1575 1900);
DISPLAY INVISIBLE (-1575 1900);
FORCEPROP 1 LAST HDL_TAP TRUE
J 0
(-1250 1825);
DISPLAY 1.234043 (-1250 1825);
PAINT GREEN (-1250 1825);
DISPLAY INVISIBLE (-1250 1825);
FORCEPROP 1 LAST PATH I22
J 0
(-1577 1950);
DISPLAY 0.872340 (-1577 1950);
PAINT GREEN (-1577 1950);
DISPLAY INVISIBLE (-1577 1950);
FORCEADD TAP..6
(-1575 2000);
FORCEPROP 3 LASTPIN (-1525 2000) SIG_NAME M_B_ECC<3>
J 0
(-1515 2010);
DISPLAY 0.659574 (-1515 2010);
PAINT MONO (-1515 2010);
DISPLAY INVISIBLE (-1515 2010);
FORCEPROP 1 LASTPIN (-1525 2000) BN 3
J 0
(-1575 2010);
DISPLAY 0.617021 (-1575 2010);
PAINT PINK (-1575 2010);
FORCEPROP 2 LAST CDS_LIB mstr_standard
J 0
(-1575 2000);
DISPLAY 0.787234 (-1575 2000);
PAINT MONO (-1575 2000);
DISPLAY INVISIBLE (-1575 2000);
FORCEPROP 1 LAST BODY_TYPE PLUMBING
J 0
(-1575 1950);
DISPLAY 1.234043 (-1575 1950);
PAINT GREEN (-1575 1950);
DISPLAY INVISIBLE (-1575 1950);
FORCEPROP 1 LAST HDL_TAP TRUE
J 0
(-1250 1875);
DISPLAY 1.234043 (-1250 1875);
PAINT GREEN (-1250 1875);
DISPLAY INVISIBLE (-1250 1875);
FORCEPROP 1 LAST PATH I23
J 0
(-1577 2000);
DISPLAY 0.872340 (-1577 2000);
PAINT GREEN (-1577 2000);
DISPLAY INVISIBLE (-1577 2000);
FORCEADD TAP..6
(-1575 2050);
FORCEPROP 3 LASTPIN (-1525 2050) SIG_NAME M_B_ECC<4>
J 0
(-1515 2060);
DISPLAY 0.659574 (-1515 2060);
PAINT MONO (-1515 2060);
DISPLAY INVISIBLE (-1515 2060);
FORCEPROP 1 LASTPIN (-1525 2050) BN 4
J 0
(-1575 2060);
DISPLAY 0.617021 (-1575 2060);
PAINT PINK (-1575 2060);
FORCEPROP 2 LAST CDS_LIB mstr_standard
J 0
(-1575 2050);
DISPLAY 0.787234 (-1575 2050);
PAINT MONO (-1575 2050);
DISPLAY INVISIBLE (-1575 2050);
FORCEPROP 1 LAST BODY_TYPE PLUMBING
J 0
(-1575 2000);
DISPLAY 1.234043 (-1575 2000);
PAINT GREEN (-1575 2000);
DISPLAY INVISIBLE (-1575 2000);
FORCEPROP 1 LAST HDL_TAP TRUE
J 0
(-1250 1925);
DISPLAY 1.234043 (-1250 1925);
PAINT GREEN (-1250 1925);
DISPLAY INVISIBLE (-1250 1925);
FORCEPROP 1 LAST PATH I24
J 0
(-1577 2050);
DISPLAY 0.872340 (-1577 2050);
PAINT GREEN (-1577 2050);
DISPLAY INVISIBLE (-1577 2050);
FORCEADD TAP..6
(-1575 2150);
FORCEPROP 3 LASTPIN (-1525 2150) SIG_NAME M_B_ECC<6>
J 0
(-1515 2160);
DISPLAY 0.659574 (-1515 2160);
PAINT MONO (-1515 2160);
DISPLAY INVISIBLE (-1515 2160);
FORCEPROP 1 LASTPIN (-1525 2150) BN 6
J 0
(-1575 2160);
DISPLAY 0.617021 (-1575 2160);
PAINT PINK (-1575 2160);
FORCEPROP 2 LAST CDS_LIB mstr_standard
J 0
(-1575 2150);
DISPLAY 0.787234 (-1575 2150);
PAINT MONO (-1575 2150);
DISPLAY INVISIBLE (-1575 2150);
FORCEPROP 1 LAST BODY_TYPE PLUMBING
J 0
(-1575 2100);
DISPLAY 1.234043 (-1575 2100);
PAINT GREEN (-1575 2100);
DISPLAY INVISIBLE (-1575 2100);
FORCEPROP 1 LAST HDL_TAP TRUE
J 0
(-1250 2025);
DISPLAY 1.234043 (-1250 2025);
PAINT GREEN (-1250 2025);
DISPLAY INVISIBLE (-1250 2025);
FORCEPROP 1 LAST PATH I25
J 0
(-1577 2150);
DISPLAY 0.872340 (-1577 2150);
PAINT GREEN (-1577 2150);
DISPLAY INVISIBLE (-1577 2150);
FORCEADD TAP..6
(-1575 2100);
FORCEPROP 3 LASTPIN (-1525 2100) SIG_NAME M_B_ECC<5>
J 0
(-1515 2110);
DISPLAY 0.659574 (-1515 2110);
PAINT MONO (-1515 2110);
DISPLAY INVISIBLE (-1515 2110);
FORCEPROP 1 LASTPIN (-1525 2100) BN 5
J 0
(-1575 2110);
DISPLAY 0.617021 (-1575 2110);
PAINT PINK (-1575 2110);
FORCEPROP 2 LAST CDS_LIB mstr_standard
J 0
(-1575 2100);
DISPLAY 0.787234 (-1575 2100);
PAINT MONO (-1575 2100);
DISPLAY INVISIBLE (-1575 2100);
FORCEPROP 1 LAST BODY_TYPE PLUMBING
J 0
(-1575 2050);
DISPLAY 1.234043 (-1575 2050);
PAINT GREEN (-1575 2050);
DISPLAY INVISIBLE (-1575 2050);
FORCEPROP 1 LAST HDL_TAP TRUE
J 0
(-1250 1975);
DISPLAY 1.234043 (-1250 1975);
PAINT GREEN (-1250 1975);
DISPLAY INVISIBLE (-1250 1975);
FORCEPROP 1 LAST PATH I26
J 0
(-1577 2100);
DISPLAY 0.872340 (-1577 2100);
PAINT GREEN (-1577 2100);
DISPLAY INVISIBLE (-1577 2100);
FORCEADD TAP..6
(-1575 2200);
FORCEPROP 3 LASTPIN (-1525 2200) SIG_NAME M_B_ECC<7>
J 0
(-1515 2210);
DISPLAY 0.659574 (-1515 2210);
PAINT MONO (-1515 2210);
DISPLAY INVISIBLE (-1515 2210);
FORCEPROP 1 LASTPIN (-1525 2200) BN 7
J 0
(-1575 2210);
DISPLAY 0.617021 (-1575 2210);
PAINT PINK (-1575 2210);
FORCEPROP 2 LAST CDS_LIB mstr_standard
J 0
(-1575 2200);
DISPLAY 0.787234 (-1575 2200);
PAINT MONO (-1575 2200);
DISPLAY INVISIBLE (-1575 2200);
FORCEPROP 1 LAST BODY_TYPE PLUMBING
J 0
(-1575 2150);
DISPLAY 1.234043 (-1575 2150);
PAINT GREEN (-1575 2150);
DISPLAY INVISIBLE (-1575 2150);
FORCEPROP 1 LAST HDL_TAP TRUE
J 0
(-1250 2075);
DISPLAY 1.234043 (-1250 2075);
PAINT GREEN (-1250 2075);
DISPLAY INVISIBLE (-1250 2075);
FORCEPROP 1 LAST PATH I27
J 0
(-1577 2200);
DISPLAY 0.872340 (-1577 2200);
PAINT GREEN (-1577 2200);
DISPLAY INVISIBLE (-1577 2200);
FORCEADD TAP..6
(-1575 2350);
FORCEPROP 3 LASTPIN (-1525 2350) SIG_NAME M_B_ODT<3>
J 0
(-1515 2360);
DISPLAY 0.659574 (-1515 2360);
PAINT MONO (-1515 2360);
DISPLAY INVISIBLE (-1515 2360);
FORCEPROP 1 LASTPIN (-1525 2350) BN 3
J 0
(-1575 2360);
DISPLAY 0.617021 (-1575 2360);
PAINT PINK (-1575 2360);
FORCEPROP 2 LAST CDS_LIB mstr_standard
J 0
(-1575 2350);
DISPLAY 0.787234 (-1575 2350);
PAINT MONO (-1575 2350);
DISPLAY INVISIBLE (-1575 2350);
FORCEPROP 1 LAST BODY_TYPE PLUMBING
J 0
(-1575 2300);
DISPLAY 1.234043 (-1575 2300);
PAINT GREEN (-1575 2300);
DISPLAY INVISIBLE (-1575 2300);
FORCEPROP 1 LAST HDL_TAP TRUE
J 0
(-1250 2225);
DISPLAY 1.234043 (-1250 2225);
PAINT GREEN (-1250 2225);
DISPLAY INVISIBLE (-1250 2225);
FORCEPROP 1 LAST PATH I28
J 0
(-1577 2350);
DISPLAY 0.872340 (-1577 2350);
PAINT GREEN (-1577 2350);
DISPLAY INVISIBLE (-1577 2350);
FORCEADD TAP..6
(-1575 2300);
FORCEPROP 3 LASTPIN (-1525 2300) SIG_NAME M_B_ODT<2>
J 0
(-1515 2310);
DISPLAY 0.659574 (-1515 2310);
PAINT MONO (-1515 2310);
DISPLAY INVISIBLE (-1515 2310);
FORCEPROP 1 LASTPIN (-1525 2300) BN 2
J 0
(-1575 2310);
DISPLAY 0.617021 (-1575 2310);
PAINT PINK (-1575 2310);
FORCEPROP 2 LAST CDS_LIB mstr_standard
J 0
(-1575 2300);
DISPLAY 0.787234 (-1575 2300);
PAINT MONO (-1575 2300);
DISPLAY INVISIBLE (-1575 2300);
FORCEPROP 1 LAST BODY_TYPE PLUMBING
J 0
(-1575 2250);
DISPLAY 1.234043 (-1575 2250);
PAINT GREEN (-1575 2250);
DISPLAY INVISIBLE (-1575 2250);
FORCEPROP 1 LAST HDL_TAP TRUE
J 0
(-1250 2175);
DISPLAY 1.234043 (-1250 2175);
PAINT GREEN (-1250 2175);
DISPLAY INVISIBLE (-1250 2175);
FORCEPROP 1 LAST PATH I29
J 0
(-1577 2300);
DISPLAY 0.872340 (-1577 2300);
PAINT GREEN (-1577 2300);
DISPLAY INVISIBLE (-1577 2300);
FORCEADD GND..1
R 2
(-3425 1250);
FORCEPROP 3 LASTPIN (-3425 1300) SIG_NAME GND\g
J 0
(-3415 1310);
DISPLAY 0.659574 (-3415 1310);
PAINT MONO (-3415 1310);
DISPLAY INVISIBLE (-3415 1310);
FORCEPROP 1 LAST VOLTAGE 0
J 0
(-3425 1250);
PAINT SKYBLUE (-3425 1250);
DISPLAY INVISIBLE (-3425 1250);
FORCEPROP 1 LAST SIZE 1B
J 2
(-3500 1200);
DISPLAY 1.170213 (-3500 1200);
PAINT GREEN (-3500 1200);
DISPLAY INVISIBLE (-3500 1200);
FORCEPROP 2 LAST CDS_LIB mstr_symbols
J 0
(-3425 1250);
DISPLAY 0.787234 (-3425 1250);
PAINT MONO (-3425 1250);
DISPLAY INVISIBLE (-3425 1250);
FORCEPROP 2 LAST BOM_COST MEM
J 0
(-3425 1255);
PAINT ORANGE (-3425 1255);
DISPLAY INVISIBLE (-3425 1255);
FORCEPROP 1 LAST BODY_TYPE PLUMBING
J 2
(-3380 1207);
DISPLAY 0.340426 (-3380 1207);
PAINT GREEN (-3380 1207);
DISPLAY INVISIBLE (-3380 1207);
FORCEPROP 1 LAST PATH I3
J 2
(-3500 1250);
DISPLAY 0.872340 (-3500 1250);
PAINT AQUA (-3500 1250);
DISPLAY INVISIBLE (-3500 1250);
FORCEPROP 2 LAST ROOM DDR4_CH_A
J 0
(-3425 1255);
PAINT ORANGE (-3425 1255);
DISPLAY INVISIBLE (-3425 1255);
FORCEPROP 1 LAST HDL_POWER GND
J 2
(-3425 1400);
DISPLAY 0.553191 (-3425 1400);
PAINT GREEN (-3425 1400);
DISPLAY INVISIBLE (-3425 1400);
FORCEADD TAP..6
(-1575 2450);
FORCEPROP 3 LASTPIN (-1525 2450) SIG_NAME M_B_CKE<2>
J 0
(-1515 2460);
DISPLAY 0.659574 (-1515 2460);
PAINT MONO (-1515 2460);
DISPLAY INVISIBLE (-1515 2460);
FORCEPROP 1 LASTPIN (-1525 2450) BN 2
J 0
(-1575 2460);
DISPLAY 0.617021 (-1575 2460);
PAINT PINK (-1575 2460);
FORCEPROP 2 LAST CDS_LIB mstr_standard
J 0
(-1575 2450);
DISPLAY 0.787234 (-1575 2450);
PAINT MONO (-1575 2450);
DISPLAY INVISIBLE (-1575 2450);
FORCEPROP 1 LAST BODY_TYPE PLUMBING
J 0
(-1575 2400);
DISPLAY 1.234043 (-1575 2400);
PAINT GREEN (-1575 2400);
DISPLAY INVISIBLE (-1575 2400);
FORCEPROP 1 LAST HDL_TAP TRUE
J 0
(-1250 2325);
DISPLAY 1.234043 (-1250 2325);
PAINT GREEN (-1250 2325);
DISPLAY INVISIBLE (-1250 2325);
FORCEPROP 1 LAST PATH I30
J 0
(-1577 2450);
DISPLAY 0.872340 (-1577 2450);
PAINT GREEN (-1577 2450);
DISPLAY INVISIBLE (-1577 2450);
FORCEADD TAP..6
(-1575 2650);
FORCEPROP 3 LASTPIN (-1525 2650) SIG_NAME M_B_CS_N<5>
J 0
(-1515 2660);
DISPLAY 0.659574 (-1515 2660);
PAINT MONO (-1515 2660);
DISPLAY INVISIBLE (-1515 2660);
FORCEPROP 1 LASTPIN (-1525 2650) BN 5
J 0
(-1575 2660);
DISPLAY 0.617021 (-1575 2660);
PAINT PINK (-1575 2660);
FORCEPROP 2 LAST CDS_LIB mstr_standard
J 0
(-1575 2650);
DISPLAY 0.787234 (-1575 2650);
PAINT MONO (-1575 2650);
DISPLAY INVISIBLE (-1575 2650);
FORCEPROP 1 LAST BODY_TYPE PLUMBING
J 0
(-1575 2600);
DISPLAY 1.234043 (-1575 2600);
PAINT GREEN (-1575 2600);
DISPLAY INVISIBLE (-1575 2600);
FORCEPROP 1 LAST HDL_TAP TRUE
J 0
(-1250 2525);
DISPLAY 1.234043 (-1250 2525);
PAINT GREEN (-1250 2525);
DISPLAY INVISIBLE (-1250 2525);
FORCEPROP 1 LAST PATH I31
J 0
(-1577 2650);
DISPLAY 0.872340 (-1577 2650);
PAINT GREEN (-1577 2650);
DISPLAY INVISIBLE (-1577 2650);
FORCEADD TAP..6
(-1575 2600);
FORCEPROP 3 LASTPIN (-1525 2600) SIG_NAME M_B_CS_N<4>
J 0
(-1515 2610);
DISPLAY 0.659574 (-1515 2610);
PAINT MONO (-1515 2610);
DISPLAY INVISIBLE (-1515 2610);
FORCEPROP 1 LASTPIN (-1525 2600) BN 4
J 0
(-1575 2610);
DISPLAY 0.617021 (-1575 2610);
PAINT PINK (-1575 2610);
FORCEPROP 2 LAST CDS_LIB mstr_standard
J 0
(-1575 2600);
DISPLAY 0.787234 (-1575 2600);
PAINT MONO (-1575 2600);
DISPLAY INVISIBLE (-1575 2600);
FORCEPROP 1 LAST BODY_TYPE PLUMBING
J 0
(-1575 2550);
DISPLAY 1.234043 (-1575 2550);
PAINT GREEN (-1575 2550);
DISPLAY INVISIBLE (-1575 2550);
FORCEPROP 1 LAST HDL_TAP TRUE
J 0
(-1250 2475);
DISPLAY 1.234043 (-1250 2475);
PAINT GREEN (-1250 2475);
DISPLAY INVISIBLE (-1250 2475);
FORCEPROP 1 LAST PATH I32
J 0
(-1577 2600);
DISPLAY 0.872340 (-1577 2600);
PAINT GREEN (-1577 2600);
DISPLAY INVISIBLE (-1577 2600);
FORCEADD TAP..6
(-1575 2500);
FORCEPROP 3 LASTPIN (-1525 2500) SIG_NAME M_B_CKE<3>
J 0
(-1515 2510);
DISPLAY 0.659574 (-1515 2510);
PAINT MONO (-1515 2510);
DISPLAY INVISIBLE (-1515 2510);
FORCEPROP 1 LASTPIN (-1525 2500) BN 3
J 0
(-1575 2510);
DISPLAY 0.617021 (-1575 2510);
PAINT PINK (-1575 2510);
FORCEPROP 2 LAST CDS_LIB mstr_standard
J 0
(-1575 2500);
DISPLAY 0.787234 (-1575 2500);
PAINT MONO (-1575 2500);
DISPLAY INVISIBLE (-1575 2500);
FORCEPROP 1 LAST BODY_TYPE PLUMBING
J 0
(-1575 2450);
DISPLAY 1.234043 (-1575 2450);
PAINT GREEN (-1575 2450);
DISPLAY INVISIBLE (-1575 2450);
FORCEPROP 1 LAST HDL_TAP TRUE
J 0
(-1250 2375);
DISPLAY 1.234043 (-1250 2375);
PAINT GREEN (-1250 2375);
DISPLAY INVISIBLE (-1250 2375);
FORCEPROP 1 LAST PATH I33
J 0
(-1577 2500);
DISPLAY 0.872340 (-1577 2500);
PAINT GREEN (-1577 2500);
DISPLAY INVISIBLE (-1577 2500);
FORCEADD TAP..6
(-1575 2700);
FORCEPROP 3 LASTPIN (-1525 2700) SIG_NAME M_B_CS_N<6>
J 0
(-1515 2710);
DISPLAY 0.659574 (-1515 2710);
PAINT MONO (-1515 2710);
DISPLAY INVISIBLE (-1515 2710);
FORCEPROP 1 LASTPIN (-1525 2700) BN 6
J 0
(-1575 2710);
DISPLAY 0.617021 (-1575 2710);
PAINT PINK (-1575 2710);
FORCEPROP 2 LAST CDS_LIB mstr_standard
J 0
(-1575 2700);
DISPLAY 0.787234 (-1575 2700);
PAINT MONO (-1575 2700);
DISPLAY INVISIBLE (-1575 2700);
FORCEPROP 1 LAST BODY_TYPE PLUMBING
J 0
(-1575 2650);
DISPLAY 1.234043 (-1575 2650);
PAINT GREEN (-1575 2650);
DISPLAY INVISIBLE (-1575 2650);
FORCEPROP 1 LAST HDL_TAP TRUE
J 0
(-1250 2575);
DISPLAY 1.234043 (-1250 2575);
PAINT GREEN (-1250 2575);
DISPLAY INVISIBLE (-1250 2575);
FORCEPROP 1 LAST PATH I34
J 0
(-1577 2700);
DISPLAY 0.872340 (-1577 2700);
PAINT GREEN (-1577 2700);
DISPLAY INVISIBLE (-1577 2700);
FORCEADD OFFPAGE..1
(-2225 2800);
FORCEPROP 2 LAST $XR0 24 
J 0
(-2476 2800);
DISPLAY 0.638298 (-2476 2800);
PAINT MONO (-2476 2800);
FORCEPROP 2 LAST $XR1 45 
J 0
(-2566 2800);
DISPLAY 0.638298 (-2566 2800);
PAINT MONO (-2566 2800);
FORCEPROP 2 LAST CDS_LIB mstr_standard
J 0
(-2225 2800);
DISPLAY 0.787234 (-2225 2800);
PAINT MONO (-2225 2800);
DISPLAY INVISIBLE (-2225 2800);
FORCEPROP 1 LAST OFFPAGE TRUE
J 0
(-1900 2675);
DISPLAY 0.936170 (-1900 2675);
PAINT GREEN (-1900 2675);
DISPLAY INVISIBLE (-1900 2675);
FORCEPROP 1 LAST COMMENT_BODY TRUE
J 0
(-2100 2700);
DISPLAY 0.936170 (-2100 2700);
PAINT GREEN (-2100 2700);
DISPLAY INVISIBLE (-2100 2700);
FORCEPROP 2 LAST PATH I35
J 0
(-2425 2850);
DISPLAY 1.021277 (-2425 2850);
PAINT ORANGE (-2425 2850);
DISPLAY INVISIBLE (-2425 2850);
FORCEADD OFFPAGE..1
(-2225 2850);
FORCEPROP 2 LAST $XR0 24 
J 0
(-2476 2850);
DISPLAY 0.638298 (-2476 2850);
PAINT MONO (-2476 2850);
FORCEPROP 2 LAST $XR1 45 
J 0
(-2566 2850);
DISPLAY 0.638298 (-2566 2850);
PAINT MONO (-2566 2850);
FORCEPROP 2 LAST CDS_LIB mstr_standard
J 0
(-2225 2850);
DISPLAY 0.787234 (-2225 2850);
PAINT MONO (-2225 2850);
DISPLAY INVISIBLE (-2225 2850);
FORCEPROP 1 LAST OFFPAGE TRUE
J 0
(-1900 2725);
DISPLAY 0.936170 (-1900 2725);
PAINT GREEN (-1900 2725);
DISPLAY INVISIBLE (-1900 2725);
FORCEPROP 1 LAST COMMENT_BODY TRUE
J 0
(-2100 2750);
DISPLAY 0.936170 (-2100 2750);
PAINT GREEN (-2100 2750);
DISPLAY INVISIBLE (-2100 2750);
FORCEPROP 2 LAST PATH I36
J 0
(-2425 2900);
DISPLAY 1.021277 (-2425 2900);
PAINT ORANGE (-2425 2900);
DISPLAY INVISIBLE (-2425 2900);
FORCEADD OFFPAGE..1
(-2225 3250);
FORCEPROP 2 LAST $XR0 24 
J 0
(-2476 3250);
DISPLAY 0.638298 (-2476 3250);
PAINT MONO (-2476 3250);
FORCEPROP 2 LAST $XR1 45 
J 0
(-2566 3250);
DISPLAY 0.638298 (-2566 3250);
PAINT MONO (-2566 3250);
FORCEPROP 2 LAST CDS_LIB mstr_standard
J 0
(-2225 3250);
DISPLAY 0.787234 (-2225 3250);
PAINT MONO (-2225 3250);
DISPLAY INVISIBLE (-2225 3250);
FORCEPROP 1 LAST OFFPAGE TRUE
J 0
(-1900 3125);
DISPLAY 0.936170 (-1900 3125);
PAINT GREEN (-1900 3125);
DISPLAY INVISIBLE (-1900 3125);
FORCEPROP 1 LAST COMMENT_BODY TRUE
J 0
(-2100 3150);
DISPLAY 0.936170 (-2100 3150);
PAINT GREEN (-2100 3150);
DISPLAY INVISIBLE (-2100 3150);
FORCEPROP 2 LAST PATH I37
J 0
(-2425 3300);
DISPLAY 1.021277 (-2425 3300);
PAINT ORANGE (-2425 3300);
DISPLAY INVISIBLE (-2425 3300);
FORCEADD OFFPAGE..1
(-2225 3350);
FORCEPROP 2 LAST $XR0 24 
J 0
(-2476 3350);
DISPLAY 0.638298 (-2476 3350);
PAINT MONO (-2476 3350);
FORCEPROP 2 LAST $XR1 45 
J 0
(-2566 3350);
DISPLAY 0.638298 (-2566 3350);
PAINT MONO (-2566 3350);
FORCEPROP 2 LAST CDS_LIB mstr_standard
J 0
(-2225 3350);
DISPLAY 0.787234 (-2225 3350);
PAINT MONO (-2225 3350);
DISPLAY INVISIBLE (-2225 3350);
FORCEPROP 1 LAST OFFPAGE TRUE
J 0
(-1900 3225);
DISPLAY 0.936170 (-1900 3225);
PAINT GREEN (-1900 3225);
DISPLAY INVISIBLE (-1900 3225);
FORCEPROP 1 LAST COMMENT_BODY TRUE
J 0
(-2100 3250);
DISPLAY 0.936170 (-2100 3250);
PAINT GREEN (-2100 3250);
DISPLAY INVISIBLE (-2100 3250);
FORCEPROP 2 LAST PATH I38
J 0
(-2425 3400);
DISPLAY 1.021277 (-2425 3400);
PAINT ORANGE (-2425 3400);
DISPLAY INVISIBLE (-2425 3400);
FORCEADD TAP..6
(-1775 2900);
FORCEPROP 3 LASTPIN (-1725 2900) SIG_NAME M_B_CLK_DN<2>
J 0
(-1715 2910);
DISPLAY 0.659574 (-1715 2910);
PAINT MONO (-1715 2910);
DISPLAY INVISIBLE (-1715 2910);
FORCEPROP 1 LASTPIN (-1725 2900) BN 2
J 0
(-1775 2910);
DISPLAY 0.617021 (-1775 2910);
PAINT PINK (-1775 2910);
FORCEPROP 2 LAST CDS_LIB mstr_standard
J 0
(-1775 2900);
DISPLAY 0.787234 (-1775 2900);
PAINT MONO (-1775 2900);
DISPLAY INVISIBLE (-1775 2900);
FORCEPROP 1 LAST BODY_TYPE PLUMBING
J 0
(-1775 2850);
DISPLAY 1.234043 (-1775 2850);
PAINT GREEN (-1775 2850);
DISPLAY INVISIBLE (-1775 2850);
FORCEPROP 1 LAST HDL_TAP TRUE
J 0
(-1450 2775);
DISPLAY 1.234043 (-1450 2775);
PAINT GREEN (-1450 2775);
DISPLAY INVISIBLE (-1450 2775);
FORCEPROP 1 LAST PATH I39
J 0
(-1777 2900);
DISPLAY 0.872340 (-1777 2900);
PAINT GREEN (-1777 2900);
DISPLAY INVISIBLE (-1777 2900);
FORCEADD PVPP_ABC..1
(-3425 1600);
FORCEPROP 3 LASTPIN (-3425 1550) SIG_NAME PVPP_ABC\g
J 0
(-3415 1560);
DISPLAY 0.659574 (-3415 1560);
PAINT MONO (-3415 1560);
DISPLAY INVISIBLE (-3415 1560);
FORCEPROP 1 LAST VOLTAGE 2.5V
J 0
(-3470 1557);
DISPLAY 0.340426 (-3470 1557);
PAINT SKYBLUE (-3470 1557);
DISPLAY INVISIBLE (-3470 1557);
FORCEPROP 0 LAST BOM_COST MEM
J 0
(-3425 1700);
PAINT ORANGE (-3425 1700);
DISPLAY INVISIBLE (-3425 1700);
FORCEPROP 2 LAST CDS_LIB mstr_symbols
J 0
(-3425 1600);
PAINT ORANGE (-3425 1600);
DISPLAY INVISIBLE (-3425 1600);
FORCEPROP 1 LAST BODY_TYPE PLUMBING
J 0
(-3470 1557);
DISPLAY 0.340426 (-3470 1557);
PAINT GREEN (-3470 1557);
DISPLAY INVISIBLE (-3470 1557);
FORCEPROP 1 LAST PATH I4
J 0
(-3375 1625);
DISPLAY 0.872340 (-3375 1625);
PAINT AQUA (-3375 1625);
DISPLAY INVISIBLE (-3375 1625);
FORCEPROP 2 LAST ROOM DDR4_CH_A
J 0
(-3425 1700);
PAINT ORANGE (-3425 1700);
DISPLAY INVISIBLE (-3425 1700);
FORCEPROP 1 LAST HDL_POWER PVPP_ABC
J 1
(-3425 1650);
DISPLAY 0.872340 (-3425 1650);
PAINT GREEN (-3425 1650);
DISPLAY INVISIBLE (-3425 1650);
FORCEADD TAP..6
(-1775 3000);
FORCEPROP 3 LASTPIN (-1725 3000) SIG_NAME M_B_CLK_DN<3>
J 0
(-1715 3010);
DISPLAY 0.659574 (-1715 3010);
PAINT MONO (-1715 3010);
DISPLAY INVISIBLE (-1715 3010);
FORCEPROP 1 LASTPIN (-1725 3000) BN 3
J 0
(-1775 3010);
DISPLAY 0.617021 (-1775 3010);
PAINT PINK (-1775 3010);
FORCEPROP 2 LAST CDS_LIB mstr_standard
J 0
(-1775 3000);
DISPLAY 0.787234 (-1775 3000);
PAINT MONO (-1775 3000);
DISPLAY INVISIBLE (-1775 3000);
FORCEPROP 1 LAST BODY_TYPE PLUMBING
J 0
(-1775 2950);
DISPLAY 1.234043 (-1775 2950);
PAINT GREEN (-1775 2950);
DISPLAY INVISIBLE (-1775 2950);
FORCEPROP 1 LAST HDL_TAP TRUE
J 0
(-1450 2875);
DISPLAY 1.234043 (-1450 2875);
PAINT GREEN (-1450 2875);
DISPLAY INVISIBLE (-1450 2875);
FORCEPROP 1 LAST PATH I40
J 0
(-1777 3000);
DISPLAY 0.872340 (-1777 3000);
PAINT GREEN (-1777 3000);
DISPLAY INVISIBLE (-1777 3000);
FORCEADD TAP..6
(-1575 2750);
FORCEPROP 3 LASTPIN (-1525 2750) SIG_NAME M_B_CS_N<7>
J 0
(-1515 2760);
DISPLAY 0.659574 (-1515 2760);
PAINT MONO (-1515 2760);
DISPLAY INVISIBLE (-1515 2760);
FORCEPROP 1 LASTPIN (-1525 2750) BN 7
J 0
(-1575 2760);
DISPLAY 0.617021 (-1575 2760);
PAINT PINK (-1575 2760);
FORCEPROP 2 LAST CDS_LIB mstr_standard
J 0
(-1575 2750);
DISPLAY 0.787234 (-1575 2750);
PAINT MONO (-1575 2750);
DISPLAY INVISIBLE (-1575 2750);
FORCEPROP 1 LAST BODY_TYPE PLUMBING
J 0
(-1575 2700);
DISPLAY 1.234043 (-1575 2700);
PAINT GREEN (-1575 2700);
DISPLAY INVISIBLE (-1575 2700);
FORCEPROP 1 LAST HDL_TAP TRUE
J 0
(-1250 2625);
DISPLAY 1.234043 (-1250 2625);
PAINT GREEN (-1250 2625);
DISPLAY INVISIBLE (-1250 2625);
FORCEPROP 1 LAST PATH I41
J 0
(-1577 2750);
DISPLAY 0.872340 (-1577 2750);
PAINT GREEN (-1577 2750);
DISPLAY INVISIBLE (-1577 2750);
FORCEADD TAP..6
(-1575 2950);
FORCEPROP 3 LASTPIN (-1525 2950) SIG_NAME M_B_CLK_DP<2>
J 0
(-1515 2960);
DISPLAY 0.659574 (-1515 2960);
PAINT MONO (-1515 2960);
DISPLAY INVISIBLE (-1515 2960);
FORCEPROP 1 LASTPIN (-1525 2950) BN 2
J 0
(-1575 2960);
DISPLAY 0.617021 (-1575 2960);
PAINT PINK (-1575 2960);
FORCEPROP 2 LAST CDS_LIB mstr_standard
J 0
(-1575 2950);
DISPLAY 0.787234 (-1575 2950);
PAINT MONO (-1575 2950);
DISPLAY INVISIBLE (-1575 2950);
FORCEPROP 1 LAST BODY_TYPE PLUMBING
J 0
(-1575 2900);
DISPLAY 1.234043 (-1575 2900);
PAINT GREEN (-1575 2900);
DISPLAY INVISIBLE (-1575 2900);
FORCEPROP 1 LAST HDL_TAP TRUE
J 0
(-1250 2825);
DISPLAY 1.234043 (-1250 2825);
PAINT GREEN (-1250 2825);
DISPLAY INVISIBLE (-1250 2825);
FORCEPROP 1 LAST PATH I42
J 0
(-1577 2950);
DISPLAY 0.872340 (-1577 2950);
PAINT GREEN (-1577 2950);
DISPLAY INVISIBLE (-1577 2950);
FORCEADD TAP..6
(-1575 3150);
FORCEPROP 3 LASTPIN (-1525 3150) SIG_NAME M_B_BG<0>
J 0
(-1515 3160);
DISPLAY 0.659574 (-1515 3160);
PAINT MONO (-1515 3160);
DISPLAY INVISIBLE (-1515 3160);
FORCEPROP 1 LASTPIN (-1525 3150) BN 0
J 0
(-1575 3160);
DISPLAY 0.617021 (-1575 3160);
PAINT PINK (-1575 3160);
FORCEPROP 2 LAST CDS_LIB mstr_standard
J 0
(-1575 3150);
DISPLAY 0.787234 (-1575 3150);
PAINT MONO (-1575 3150);
DISPLAY INVISIBLE (-1575 3150);
FORCEPROP 1 LAST BODY_TYPE PLUMBING
J 0
(-1575 3100);
DISPLAY 1.234043 (-1575 3100);
PAINT GREEN (-1575 3100);
DISPLAY INVISIBLE (-1575 3100);
FORCEPROP 1 LAST HDL_TAP TRUE
J 0
(-1250 3025);
DISPLAY 1.234043 (-1250 3025);
PAINT GREEN (-1250 3025);
DISPLAY INVISIBLE (-1250 3025);
FORCEPROP 1 LAST PATH I43
J 0
(-1577 3150);
DISPLAY 0.872340 (-1577 3150);
PAINT GREEN (-1577 3150);
DISPLAY INVISIBLE (-1577 3150);
FORCEADD TAP..6
(-1575 3200);
FORCEPROP 3 LASTPIN (-1525 3200) SIG_NAME M_B_BG<1>
J 0
(-1515 3210);
DISPLAY 0.659574 (-1515 3210);
PAINT MONO (-1515 3210);
DISPLAY INVISIBLE (-1515 3210);
FORCEPROP 1 LASTPIN (-1525 3200) BN 1
J 0
(-1575 3210);
DISPLAY 0.617021 (-1575 3210);
PAINT PINK (-1575 3210);
FORCEPROP 2 LAST CDS_LIB mstr_standard
J 0
(-1575 3200);
DISPLAY 0.787234 (-1575 3200);
PAINT MONO (-1575 3200);
DISPLAY INVISIBLE (-1575 3200);
FORCEPROP 1 LAST BODY_TYPE PLUMBING
J 0
(-1575 3150);
DISPLAY 1.234043 (-1575 3150);
PAINT GREEN (-1575 3150);
DISPLAY INVISIBLE (-1575 3150);
FORCEPROP 1 LAST HDL_TAP TRUE
J 0
(-1250 3075);
DISPLAY 1.234043 (-1250 3075);
PAINT GREEN (-1250 3075);
DISPLAY INVISIBLE (-1250 3075);
FORCEPROP 1 LAST PATH I44
J 0
(-1577 3200);
DISPLAY 0.872340 (-1577 3200);
PAINT GREEN (-1577 3200);
DISPLAY INVISIBLE (-1577 3200);
FORCEADD TAP..6
(-1575 3050);
FORCEPROP 3 LASTPIN (-1525 3050) SIG_NAME M_B_CLK_DP<3>
J 0
(-1515 3060);
DISPLAY 0.659574 (-1515 3060);
PAINT MONO (-1515 3060);
DISPLAY INVISIBLE (-1515 3060);
FORCEPROP 1 LASTPIN (-1525 3050) BN 3
J 0
(-1575 3060);
DISPLAY 0.617021 (-1575 3060);
PAINT PINK (-1575 3060);
FORCEPROP 2 LAST CDS_LIB mstr_standard
J 0
(-1575 3050);
DISPLAY 0.787234 (-1575 3050);
PAINT MONO (-1575 3050);
DISPLAY INVISIBLE (-1575 3050);
FORCEPROP 1 LAST BODY_TYPE PLUMBING
J 0
(-1575 3000);
DISPLAY 1.234043 (-1575 3000);
PAINT GREEN (-1575 3000);
DISPLAY INVISIBLE (-1575 3000);
FORCEPROP 1 LAST HDL_TAP TRUE
J 0
(-1250 2925);
DISPLAY 1.234043 (-1250 2925);
PAINT GREEN (-1250 2925);
DISPLAY INVISIBLE (-1250 2925);
FORCEPROP 1 LAST PATH I45
J 0
(-1577 3050);
DISPLAY 0.872340 (-1577 3050);
PAINT GREEN (-1577 3050);
DISPLAY INVISIBLE (-1577 3050);
FORCEADD TAP..6
(-1575 3450);
FORCEPROP 3 LASTPIN (-1525 3450) SIG_NAME M_B_MA<1>
J 0
(-1515 3460);
DISPLAY 0.659574 (-1515 3460);
PAINT MONO (-1515 3460);
DISPLAY INVISIBLE (-1515 3460);
FORCEPROP 1 LASTPIN (-1525 3450) BN 1
J 0
(-1575 3460);
DISPLAY 0.617021 (-1575 3460);
PAINT PINK (-1575 3460);
FORCEPROP 2 LAST CDS_LIB mstr_standard
J 2
(-1575 3450);
DISPLAY 0.787234 (-1575 3450);
PAINT MONO (-1575 3450);
DISPLAY INVISIBLE (-1575 3450);
FORCEPROP 1 LAST BODY_TYPE PLUMBING
J 0
(-1575 3400);
DISPLAY 1.234043 (-1575 3400);
PAINT GREEN (-1575 3400);
DISPLAY INVISIBLE (-1575 3400);
FORCEPROP 1 LAST HDL_TAP TRUE
J 0
(-1250 3325);
DISPLAY 1.234043 (-1250 3325);
PAINT GREEN (-1250 3325);
DISPLAY INVISIBLE (-1250 3325);
FORCEPROP 1 LAST PATH I46
J 0
(-1577 3450);
DISPLAY 0.872340 (-1577 3450);
PAINT GREEN (-1577 3450);
DISPLAY INVISIBLE (-1577 3450);
FORCEADD TAP..6
(-1575 3400);
FORCEPROP 3 LASTPIN (-1525 3400) SIG_NAME M_B_MA<0>
J 0
(-1515 3410);
DISPLAY 0.659574 (-1515 3410);
PAINT MONO (-1515 3410);
DISPLAY INVISIBLE (-1515 3410);
FORCEPROP 1 LASTPIN (-1525 3400) BN 0
J 0
(-1575 3410);
DISPLAY 0.617021 (-1575 3410);
PAINT PINK (-1575 3410);
FORCEPROP 2 LAST CDS_LIB mstr_standard
J 2
(-1575 3400);
DISPLAY 0.787234 (-1575 3400);
PAINT MONO (-1575 3400);
DISPLAY INVISIBLE (-1575 3400);
FORCEPROP 1 LAST BODY_TYPE PLUMBING
J 0
(-1575 3350);
DISPLAY 1.234043 (-1575 3350);
PAINT GREEN (-1575 3350);
DISPLAY INVISIBLE (-1575 3350);
FORCEPROP 1 LAST HDL_TAP TRUE
J 0
(-1250 3275);
DISPLAY 1.234043 (-1250 3275);
PAINT GREEN (-1250 3275);
DISPLAY INVISIBLE (-1250 3275);
FORCEPROP 1 LAST PATH I47
J 0
(-1577 3400);
DISPLAY 0.872340 (-1577 3400);
PAINT GREEN (-1577 3400);
DISPLAY INVISIBLE (-1577 3400);
FORCEADD TAP..6
(-1575 3250);
FORCEPROP 3 LASTPIN (-1525 3250) SIG_NAME M_B_BA<0>
J 0
(-1515 3260);
DISPLAY 0.659574 (-1515 3260);
PAINT MONO (-1515 3260);
DISPLAY INVISIBLE (-1515 3260);
FORCEPROP 1 LASTPIN (-1525 3250) BN 0
J 0
(-1575 3260);
DISPLAY 0.617021 (-1575 3260);
PAINT PINK (-1575 3260);
FORCEPROP 2 LAST CDS_LIB mstr_standard
J 0
(-1575 3250);
DISPLAY 0.787234 (-1575 3250);
PAINT MONO (-1575 3250);
DISPLAY INVISIBLE (-1575 3250);
FORCEPROP 1 LAST BODY_TYPE PLUMBING
J 0
(-1575 3200);
DISPLAY 1.234043 (-1575 3200);
PAINT GREEN (-1575 3200);
DISPLAY INVISIBLE (-1575 3200);
FORCEPROP 1 LAST HDL_TAP TRUE
J 0
(-1250 3125);
DISPLAY 1.234043 (-1250 3125);
PAINT GREEN (-1250 3125);
DISPLAY INVISIBLE (-1250 3125);
FORCEPROP 1 LAST PATH I48
J 0
(-1577 3250);
DISPLAY 0.872340 (-1577 3250);
PAINT GREEN (-1577 3250);
DISPLAY INVISIBLE (-1577 3250);
FORCEADD TAP..6
(-1575 3300);
FORCEPROP 3 LASTPIN (-1525 3300) SIG_NAME M_B_BA<1>
J 0
(-1515 3310);
DISPLAY 0.659574 (-1515 3310);
PAINT MONO (-1515 3310);
DISPLAY INVISIBLE (-1515 3310);
FORCEPROP 1 LASTPIN (-1525 3300) BN 1
J 0
(-1575 3310);
DISPLAY 0.617021 (-1575 3310);
PAINT PINK (-1575 3310);
FORCEPROP 2 LAST CDS_LIB mstr_standard
J 0
(-1575 3300);
DISPLAY 0.787234 (-1575 3300);
PAINT MONO (-1575 3300);
DISPLAY INVISIBLE (-1575 3300);
FORCEPROP 1 LAST BODY_TYPE PLUMBING
J 0
(-1575 3250);
DISPLAY 1.234043 (-1575 3250);
PAINT GREEN (-1575 3250);
DISPLAY INVISIBLE (-1575 3250);
FORCEPROP 1 LAST HDL_TAP TRUE
J 0
(-1250 3175);
DISPLAY 1.234043 (-1250 3175);
PAINT GREEN (-1250 3175);
DISPLAY INVISIBLE (-1250 3175);
FORCEPROP 1 LAST PATH I49
J 0
(-1577 3300);
DISPLAY 0.872340 (-1577 3300);
PAINT GREEN (-1577 3300);
DISPLAY INVISIBLE (-1577 3300);
FORCEADD CAP_A..1
R 2
(-2975 900);
FORCEPROP 1 LAST LOCATION C6U9
J 2
(-3025 1000);
DISPLAY 0.617021 (-3025 1000);
PAINT AQUA (-3025 1000);
FORCEPROP 1 LAST PART_NUMBER A36096-045
J 2
(-3025 750);
DISPLAY 0.617021 (-3025 750);
PAINT BLUE (-3025 750);
FORCEPROP 1 LAST VALUE 0.01UF
J 2
(-3025 950);
DISPLAY 0.617021 (-3025 950);
PAINT SKYBLUE (-3025 950);
FORCEPROP 1 LAST TOLERANCE 10%
J 2
(-3025 850);
DISPLAY 0.617021 (-3025 850);
PAINT SKYBLUE (-3025 850);
FORCEPROP 1 LAST PACK_TYPE 0402V
J 2
(-3025 700);
DISPLAY 0.617021 (-3025 700);
PAINT SKYBLUE (-3025 700);
FORCEPROP 1 LAST VOLTAGE 25V
J 2
(-3025 900);
DISPLAY 0.617021 (-3025 900);
PAINT SKYBLUE (-3025 900);
FORCEPROP 1 LAST MATERIAL X7R
J 2
(-3025 800);
DISPLAY 0.617021 (-3025 800);
PAINT SKYBLUE (-3025 800);
FORCEPROP 1 LASTPIN (-2975 1000) $PN 1
J 2
(-2985 980);
DISPLAY 0.617021 (-2985 980);
PAINT ORANGE (-2985 980);
FORCEPROP 1 LASTPIN (-2975 800) $PN 2
J 2
(-2985 780);
DISPLAY 0.617021 (-2985 780);
PAINT ORANGE (-2985 780);
FORCEPROP 2 LAST CDS_LOCATION C6U9
J 2
(-3025 1000);
DISPLAY 0.617021 (-3025 1000);
PAINT AQUA (-3025 1000);
DISPLAY INVISIBLE (-3025 1000);
FORCEPROP 2 LAST BOM_COST MEM
J 0
(-2975 900);
PAINT ORANGE (-2975 900);
DISPLAY INVISIBLE (-2975 900);
FORCEPROP 2 LAST CDS_LIB dev_discrete
J 0
(-2975 900);
PAINT ORANGE (-2975 900);
DISPLAY INVISIBLE (-2975 900);
FORCEPROP 2 LAST CDS_SEC 1
J 0
(-3025 1050);
PAINT ORANGE (-3025 1050);
DISPLAY INVISIBLE (-3025 1050);
FORCEPROP 2 LAST SEC_TYPE 0402V
J 0
(-3025 1100);
DISPLAY 1.021277 (-3025 1100);
PAINT ORANGE (-3025 1100);
DISPLAY INVISIBLE (-3025 1100);
FORCEPROP 2 LAST SEC 1
J 0
(-3025 1100);
PAINT MONO (-3025 1100);
DISPLAY INVISIBLE (-3025 1100);
FORCEPROP 1 LAST PATH I5
J 2
(-3025 1050);
DISPLAY 0.978723 (-3025 1050);
PAINT WHITE (-3025 1050);
DISPLAY INVISIBLE (-3025 1050);
FORCEPROP 2 LAST ROOM DDR4_CH_A
J 0
(-2975 900);
PAINT ORANGE (-2975 900);
DISPLAY INVISIBLE (-2975 900);
FORCEADD TAP..6
(-1575 3500);
FORCEPROP 3 LASTPIN (-1525 3500) SIG_NAME M_B_MA<2>
J 0
(-1515 3510);
DISPLAY 0.659574 (-1515 3510);
PAINT MONO (-1515 3510);
DISPLAY INVISIBLE (-1515 3510);
FORCEPROP 1 LASTPIN (-1525 3500) BN 2
J 0
(-1575 3510);
DISPLAY 0.617021 (-1575 3510);
PAINT PINK (-1575 3510);
FORCEPROP 2 LAST CDS_LIB mstr_standard
J 2
(-1575 3500);
DISPLAY 0.787234 (-1575 3500);
PAINT MONO (-1575 3500);
DISPLAY INVISIBLE (-1575 3500);
FORCEPROP 1 LAST BODY_TYPE PLUMBING
J 0
(-1575 3450);
DISPLAY 1.234043 (-1575 3450);
PAINT GREEN (-1575 3450);
DISPLAY INVISIBLE (-1575 3450);
FORCEPROP 1 LAST HDL_TAP TRUE
J 0
(-1250 3375);
DISPLAY 1.234043 (-1250 3375);
PAINT GREEN (-1250 3375);
DISPLAY INVISIBLE (-1250 3375);
FORCEPROP 1 LAST PATH I50
J 0
(-1577 3500);
DISPLAY 0.872340 (-1577 3500);
PAINT GREEN (-1577 3500);
DISPLAY INVISIBLE (-1577 3500);
FORCEADD TAP..6
(-1575 3550);
FORCEPROP 3 LASTPIN (-1525 3550) SIG_NAME M_B_MA<3>
J 0
(-1515 3560);
DISPLAY 0.659574 (-1515 3560);
PAINT MONO (-1515 3560);
DISPLAY INVISIBLE (-1515 3560);
FORCEPROP 1 LASTPIN (-1525 3550) BN 3
J 0
(-1575 3560);
DISPLAY 0.617021 (-1575 3560);
PAINT PINK (-1575 3560);
FORCEPROP 2 LAST CDS_LIB mstr_standard
J 2
(-1575 3550);
DISPLAY 0.787234 (-1575 3550);
PAINT MONO (-1575 3550);
DISPLAY INVISIBLE (-1575 3550);
FORCEPROP 1 LAST BODY_TYPE PLUMBING
J 0
(-1575 3500);
DISPLAY 1.234043 (-1575 3500);
PAINT GREEN (-1575 3500);
DISPLAY INVISIBLE (-1575 3500);
FORCEPROP 1 LAST HDL_TAP TRUE
J 0
(-1250 3425);
DISPLAY 1.234043 (-1250 3425);
PAINT GREEN (-1250 3425);
DISPLAY INVISIBLE (-1250 3425);
FORCEPROP 1 LAST PATH I51
J 0
(-1577 3550);
DISPLAY 0.872340 (-1577 3550);
PAINT GREEN (-1577 3550);
DISPLAY INVISIBLE (-1577 3550);
FORCEADD TAP..6
(-1575 3700);
FORCEPROP 3 LASTPIN (-1525 3700) SIG_NAME M_B_MA<6>
J 0
(-1515 3710);
DISPLAY 0.659574 (-1515 3710);
PAINT MONO (-1515 3710);
DISPLAY INVISIBLE (-1515 3710);
FORCEPROP 1 LASTPIN (-1525 3700) BN 6
J 0
(-1575 3710);
DISPLAY 0.617021 (-1575 3710);
PAINT PINK (-1575 3710);
FORCEPROP 2 LAST CDS_LIB mstr_standard
J 2
(-1575 3700);
DISPLAY 0.787234 (-1575 3700);
PAINT MONO (-1575 3700);
DISPLAY INVISIBLE (-1575 3700);
FORCEPROP 1 LAST BODY_TYPE PLUMBING
J 0
(-1575 3650);
DISPLAY 1.234043 (-1575 3650);
PAINT GREEN (-1575 3650);
DISPLAY INVISIBLE (-1575 3650);
FORCEPROP 1 LAST HDL_TAP TRUE
J 0
(-1250 3575);
DISPLAY 1.234043 (-1250 3575);
PAINT GREEN (-1250 3575);
DISPLAY INVISIBLE (-1250 3575);
FORCEPROP 1 LAST PATH I52
J 0
(-1577 3700);
DISPLAY 0.872340 (-1577 3700);
PAINT GREEN (-1577 3700);
DISPLAY INVISIBLE (-1577 3700);
FORCEADD TAP..6
(-1575 3650);
FORCEPROP 3 LASTPIN (-1525 3650) SIG_NAME M_B_MA<5>
J 0
(-1515 3660);
DISPLAY 0.659574 (-1515 3660);
PAINT MONO (-1515 3660);
DISPLAY INVISIBLE (-1515 3660);
FORCEPROP 1 LASTPIN (-1525 3650) BN 5
J 0
(-1575 3660);
DISPLAY 0.617021 (-1575 3660);
PAINT PINK (-1575 3660);
FORCEPROP 2 LAST CDS_LIB mstr_standard
J 2
(-1575 3650);
DISPLAY 0.787234 (-1575 3650);
PAINT MONO (-1575 3650);
DISPLAY INVISIBLE (-1575 3650);
FORCEPROP 1 LAST BODY_TYPE PLUMBING
J 0
(-1575 3600);
DISPLAY 1.234043 (-1575 3600);
PAINT GREEN (-1575 3600);
DISPLAY INVISIBLE (-1575 3600);
FORCEPROP 1 LAST HDL_TAP TRUE
J 0
(-1250 3525);
DISPLAY 1.234043 (-1250 3525);
PAINT GREEN (-1250 3525);
DISPLAY INVISIBLE (-1250 3525);
FORCEPROP 1 LAST PATH I53
J 0
(-1577 3650);
DISPLAY 0.872340 (-1577 3650);
PAINT GREEN (-1577 3650);
DISPLAY INVISIBLE (-1577 3650);
FORCEADD TAP..6
(-1575 3600);
FORCEPROP 3 LASTPIN (-1525 3600) SIG_NAME M_B_MA<4>
J 0
(-1515 3610);
DISPLAY 0.659574 (-1515 3610);
PAINT MONO (-1515 3610);
DISPLAY INVISIBLE (-1515 3610);
FORCEPROP 1 LASTPIN (-1525 3600) BN 4
J 0
(-1575 3610);
DISPLAY 0.617021 (-1575 3610);
PAINT PINK (-1575 3610);
FORCEPROP 2 LAST CDS_LIB mstr_standard
J 2
(-1575 3600);
DISPLAY 0.787234 (-1575 3600);
PAINT MONO (-1575 3600);
DISPLAY INVISIBLE (-1575 3600);
FORCEPROP 1 LAST BODY_TYPE PLUMBING
J 0
(-1575 3550);
DISPLAY 1.234043 (-1575 3550);
PAINT GREEN (-1575 3550);
DISPLAY INVISIBLE (-1575 3550);
FORCEPROP 1 LAST HDL_TAP TRUE
J 0
(-1250 3475);
DISPLAY 1.234043 (-1250 3475);
PAINT GREEN (-1250 3475);
DISPLAY INVISIBLE (-1250 3475);
FORCEPROP 1 LAST PATH I54
J 0
(-1577 3600);
DISPLAY 0.872340 (-1577 3600);
PAINT GREEN (-1577 3600);
DISPLAY INVISIBLE (-1577 3600);
FORCEADD TAP..6
R 2
(-75 1150);
FORCEPROP 3 LASTPIN (-125 1150) SIG_NAME M_B_DQ<1>
J 0
(-115 1160);
DISPLAY 0.659574 (-115 1160);
PAINT MONO (-115 1160);
DISPLAY INVISIBLE (-115 1160);
FORCEPROP 1 LASTPIN (-125 1150) BN 1
J 2
(-75 1160);
DISPLAY 0.617021 (-75 1160);
PAINT PINK (-75 1160);
FORCEPROP 2 LAST CDS_LIB mstr_standard
J 2
(-75 1150);
DISPLAY 0.787234 (-75 1150);
PAINT MONO (-75 1150);
DISPLAY INVISIBLE (-75 1150);
FORCEPROP 1 LAST BODY_TYPE PLUMBING
J 2
(-75 1100);
DISPLAY 1.234043 (-75 1100);
PAINT GREEN (-75 1100);
DISPLAY INVISIBLE (-75 1100);
FORCEPROP 1 LAST HDL_TAP TRUE
J 2
(-400 1025);
DISPLAY 1.234043 (-400 1025);
PAINT GREEN (-400 1025);
DISPLAY INVISIBLE (-400 1025);
FORCEPROP 1 LAST PATH I55
J 2
(-73 1150);
DISPLAY 0.872340 (-73 1150);
PAINT GREEN (-73 1150);
DISPLAY INVISIBLE (-73 1150);
FORCEADD TAP..6
R 2
(-75 1100);
FORCEPROP 3 LASTPIN (-125 1100) SIG_NAME M_B_DQ<0>
J 0
(-115 1110);
DISPLAY 0.659574 (-115 1110);
PAINT MONO (-115 1110);
DISPLAY INVISIBLE (-115 1110);
FORCEPROP 1 LASTPIN (-125 1100) BN 0
J 2
(-75 1110);
DISPLAY 0.617021 (-75 1110);
PAINT PINK (-75 1110);
FORCEPROP 2 LAST CDS_LIB mstr_standard
J 2
(-75 1100);
DISPLAY 0.787234 (-75 1100);
PAINT MONO (-75 1100);
DISPLAY INVISIBLE (-75 1100);
FORCEPROP 1 LAST BODY_TYPE PLUMBING
J 2
(-75 1050);
DISPLAY 1.234043 (-75 1050);
PAINT GREEN (-75 1050);
DISPLAY INVISIBLE (-75 1050);
FORCEPROP 1 LAST HDL_TAP TRUE
J 2
(-400 975);
DISPLAY 1.234043 (-400 975);
PAINT GREEN (-400 975);
DISPLAY INVISIBLE (-400 975);
FORCEPROP 1 LAST PATH I56
J 2
(-73 1100);
DISPLAY 0.872340 (-73 1100);
PAINT GREEN (-73 1100);
DISPLAY INVISIBLE (-73 1100);
FORCEADD TAP..6
R 2
(-75 1250);
FORCEPROP 3 LASTPIN (-125 1250) SIG_NAME M_B_DQ<3>
J 0
(-115 1260);
DISPLAY 0.659574 (-115 1260);
PAINT MONO (-115 1260);
DISPLAY INVISIBLE (-115 1260);
FORCEPROP 1 LASTPIN (-125 1250) BN 3
J 2
(-75 1260);
DISPLAY 0.617021 (-75 1260);
PAINT PINK (-75 1260);
FORCEPROP 2 LAST CDS_LIB mstr_standard
J 2
(-75 1250);
DISPLAY 0.787234 (-75 1250);
PAINT MONO (-75 1250);
DISPLAY INVISIBLE (-75 1250);
FORCEPROP 1 LAST BODY_TYPE PLUMBING
J 2
(-75 1200);
DISPLAY 1.234043 (-75 1200);
PAINT GREEN (-75 1200);
DISPLAY INVISIBLE (-75 1200);
FORCEPROP 1 LAST HDL_TAP TRUE
J 2
(-400 1125);
DISPLAY 1.234043 (-400 1125);
PAINT GREEN (-400 1125);
DISPLAY INVISIBLE (-400 1125);
FORCEPROP 1 LAST PATH I57
J 2
(-73 1250);
DISPLAY 0.872340 (-73 1250);
PAINT GREEN (-73 1250);
DISPLAY INVISIBLE (-73 1250);
FORCEADD TAP..6
R 2
(-75 1200);
FORCEPROP 3 LASTPIN (-125 1200) SIG_NAME M_B_DQ<2>
J 0
(-115 1210);
DISPLAY 0.659574 (-115 1210);
PAINT MONO (-115 1210);
DISPLAY INVISIBLE (-115 1210);
FORCEPROP 1 LASTPIN (-125 1200) BN 2
J 2
(-75 1210);
DISPLAY 0.617021 (-75 1210);
PAINT PINK (-75 1210);
FORCEPROP 2 LAST CDS_LIB mstr_standard
J 2
(-75 1200);
DISPLAY 0.787234 (-75 1200);
PAINT MONO (-75 1200);
DISPLAY INVISIBLE (-75 1200);
FORCEPROP 1 LAST BODY_TYPE PLUMBING
J 2
(-75 1150);
DISPLAY 1.234043 (-75 1150);
PAINT GREEN (-75 1150);
DISPLAY INVISIBLE (-75 1150);
FORCEPROP 1 LAST HDL_TAP TRUE
J 2
(-400 1075);
DISPLAY 1.234043 (-400 1075);
PAINT GREEN (-400 1075);
DISPLAY INVISIBLE (-400 1075);
FORCEPROP 1 LAST PATH I58
J 2
(-73 1200);
DISPLAY 0.872340 (-73 1200);
PAINT GREEN (-73 1200);
DISPLAY INVISIBLE (-73 1200);
FORCEADD TAP..6
R 2
(-75 1300);
FORCEPROP 3 LASTPIN (-125 1300) SIG_NAME M_B_DQ<4>
J 0
(-115 1310);
DISPLAY 0.659574 (-115 1310);
PAINT MONO (-115 1310);
DISPLAY INVISIBLE (-115 1310);
FORCEPROP 1 LASTPIN (-125 1300) BN 4
J 2
(-75 1310);
DISPLAY 0.617021 (-75 1310);
PAINT PINK (-75 1310);
FORCEPROP 2 LAST CDS_LIB mstr_standard
J 2
(-75 1300);
DISPLAY 0.787234 (-75 1300);
PAINT MONO (-75 1300);
DISPLAY INVISIBLE (-75 1300);
FORCEPROP 1 LAST BODY_TYPE PLUMBING
J 2
(-75 1250);
DISPLAY 1.234043 (-75 1250);
PAINT GREEN (-75 1250);
DISPLAY INVISIBLE (-75 1250);
FORCEPROP 1 LAST HDL_TAP TRUE
J 2
(-400 1175);
DISPLAY 1.234043 (-400 1175);
PAINT GREEN (-400 1175);
DISPLAY INVISIBLE (-400 1175);
FORCEPROP 1 LAST PATH I59
J 2
(-73 1300);
DISPLAY 0.872340 (-73 1300);
PAINT GREEN (-73 1300);
DISPLAY INVISIBLE (-73 1300);
FORCEADD OFFPAGE..5
(-2400 1600);
FORCEPROP 2 LAST $XR0 45 
J 0
(-2624 1600);
DISPLAY 0.638298 (-2624 1600);
PAINT MONO (-2624 1600);
FORCEPROP 2 LAST $XR1 24 
J 0
(-2714 1600);
DISPLAY 0.638298 (-2714 1600);
PAINT MONO (-2714 1600);
FORCEPROP 2 LAST CDS_LIB mstr_standard
J 0
(-2400 1600);
DISPLAY 0.787234 (-2400 1600);
PAINT MONO (-2400 1600);
DISPLAY INVISIBLE (-2400 1600);
FORCEPROP 1 LAST OFFPAGE TRUE
J 0
(-2075 1475);
DISPLAY 1.404255 (-2075 1475);
PAINT GREEN (-2075 1475);
DISPLAY INVISIBLE (-2075 1475);
FORCEPROP 1 LAST COMMENT_BODY TRUE
J 0
(-2300 1525);
DISPLAY 1.404255 (-2300 1525);
PAINT GREEN (-2300 1525);
DISPLAY INVISIBLE (-2300 1525);
FORCEPROP 2 LAST PATH I6
J 0
(-2575 1650);
DISPLAY 1.021277 (-2575 1650);
PAINT ORANGE (-2575 1650);
DISPLAY INVISIBLE (-2575 1650);
FORCEADD TAP..6
R 2
(-75 1400);
FORCEPROP 3 LASTPIN (-125 1400) SIG_NAME M_B_DQ<6>
J 0
(-115 1410);
DISPLAY 0.659574 (-115 1410);
PAINT MONO (-115 1410);
DISPLAY INVISIBLE (-115 1410);
FORCEPROP 1 LASTPIN (-125 1400) BN 6
J 2
(-75 1410);
DISPLAY 0.617021 (-75 1410);
PAINT PINK (-75 1410);
FORCEPROP 2 LAST CDS_LIB mstr_standard
J 2
(-75 1400);
DISPLAY 0.787234 (-75 1400);
PAINT MONO (-75 1400);
DISPLAY INVISIBLE (-75 1400);
FORCEPROP 1 LAST BODY_TYPE PLUMBING
J 2
(-75 1350);
DISPLAY 1.234043 (-75 1350);
PAINT GREEN (-75 1350);
DISPLAY INVISIBLE (-75 1350);
FORCEPROP 1 LAST HDL_TAP TRUE
J 2
(-400 1275);
DISPLAY 1.234043 (-400 1275);
PAINT GREEN (-400 1275);
DISPLAY INVISIBLE (-400 1275);
FORCEPROP 1 LAST PATH I60
J 2
(-73 1400);
DISPLAY 0.872340 (-73 1400);
PAINT GREEN (-73 1400);
DISPLAY INVISIBLE (-73 1400);
FORCEADD TAP..6
R 2
(-75 1350);
FORCEPROP 3 LASTPIN (-125 1350) SIG_NAME M_B_DQ<5>
J 0
(-115 1360);
DISPLAY 0.659574 (-115 1360);
PAINT MONO (-115 1360);
DISPLAY INVISIBLE (-115 1360);
FORCEPROP 1 LASTPIN (-125 1350) BN 5
J 2
(-75 1360);
DISPLAY 0.617021 (-75 1360);
PAINT PINK (-75 1360);
FORCEPROP 2 LAST CDS_LIB mstr_standard
J 2
(-75 1350);
DISPLAY 0.787234 (-75 1350);
PAINT MONO (-75 1350);
DISPLAY INVISIBLE (-75 1350);
FORCEPROP 1 LAST BODY_TYPE PLUMBING
J 2
(-75 1300);
DISPLAY 1.234043 (-75 1300);
PAINT GREEN (-75 1300);
DISPLAY INVISIBLE (-75 1300);
FORCEPROP 1 LAST HDL_TAP TRUE
J 2
(-400 1225);
DISPLAY 1.234043 (-400 1225);
PAINT GREEN (-400 1225);
DISPLAY INVISIBLE (-400 1225);
FORCEPROP 1 LAST PATH I61
J 2
(-73 1350);
DISPLAY 0.872340 (-73 1350);
PAINT GREEN (-73 1350);
DISPLAY INVISIBLE (-73 1350);
FORCEADD TAP..6
R 2
(-75 1450);
FORCEPROP 3 LASTPIN (-125 1450) SIG_NAME M_B_DQ<7>
J 0
(-115 1460);
DISPLAY 0.659574 (-115 1460);
PAINT MONO (-115 1460);
DISPLAY INVISIBLE (-115 1460);
FORCEPROP 1 LASTPIN (-125 1450) BN 7
J 2
(-75 1460);
DISPLAY 0.617021 (-75 1460);
PAINT PINK (-75 1460);
FORCEPROP 2 LAST CDS_LIB mstr_standard
J 2
(-75 1450);
DISPLAY 0.787234 (-75 1450);
PAINT MONO (-75 1450);
DISPLAY INVISIBLE (-75 1450);
FORCEPROP 1 LAST BODY_TYPE PLUMBING
J 2
(-75 1400);
DISPLAY 1.234043 (-75 1400);
PAINT GREEN (-75 1400);
DISPLAY INVISIBLE (-75 1400);
FORCEPROP 1 LAST HDL_TAP TRUE
J 2
(-400 1325);
DISPLAY 1.234043 (-400 1325);
PAINT GREEN (-400 1325);
DISPLAY INVISIBLE (-400 1325);
FORCEPROP 1 LAST PATH I62
J 2
(-73 1450);
DISPLAY 0.872340 (-73 1450);
PAINT GREEN (-73 1450);
DISPLAY INVISIBLE (-73 1450);
FORCEADD TAP..6
R 2
(-75 1550);
FORCEPROP 3 LASTPIN (-125 1550) SIG_NAME M_B_DQ<9>
J 0
(-115 1560);
DISPLAY 0.659574 (-115 1560);
PAINT MONO (-115 1560);
DISPLAY INVISIBLE (-115 1560);
FORCEPROP 1 LASTPIN (-125 1550) BN 9
J 2
(-75 1560);
DISPLAY 0.617021 (-75 1560);
PAINT PINK (-75 1560);
FORCEPROP 2 LAST CDS_LIB mstr_standard
J 2
(-75 1550);
DISPLAY 0.787234 (-75 1550);
PAINT MONO (-75 1550);
DISPLAY INVISIBLE (-75 1550);
FORCEPROP 1 LAST BODY_TYPE PLUMBING
J 2
(-75 1500);
DISPLAY 1.234043 (-75 1500);
PAINT GREEN (-75 1500);
DISPLAY INVISIBLE (-75 1500);
FORCEPROP 1 LAST HDL_TAP TRUE
J 2
(-400 1425);
DISPLAY 1.234043 (-400 1425);
PAINT GREEN (-400 1425);
DISPLAY INVISIBLE (-400 1425);
FORCEPROP 1 LAST PATH I63
J 2
(-73 1550);
DISPLAY 0.872340 (-73 1550);
PAINT GREEN (-73 1550);
DISPLAY INVISIBLE (-73 1550);
FORCEADD TAP..6
R 2
(-75 1500);
FORCEPROP 3 LASTPIN (-125 1500) SIG_NAME M_B_DQ<8>
J 0
(-115 1510);
DISPLAY 0.659574 (-115 1510);
PAINT MONO (-115 1510);
DISPLAY INVISIBLE (-115 1510);
FORCEPROP 1 LASTPIN (-125 1500) BN 8
J 2
(-75 1510);
DISPLAY 0.617021 (-75 1510);
PAINT PINK (-75 1510);
FORCEPROP 2 LAST CDS_LIB mstr_standard
J 2
(-75 1500);
DISPLAY 0.787234 (-75 1500);
PAINT MONO (-75 1500);
DISPLAY INVISIBLE (-75 1500);
FORCEPROP 1 LAST BODY_TYPE PLUMBING
J 2
(-75 1450);
DISPLAY 1.234043 (-75 1450);
PAINT GREEN (-75 1450);
DISPLAY INVISIBLE (-75 1450);
FORCEPROP 1 LAST HDL_TAP TRUE
J 2
(-400 1375);
DISPLAY 1.234043 (-400 1375);
PAINT GREEN (-400 1375);
DISPLAY INVISIBLE (-400 1375);
FORCEPROP 1 LAST PATH I64
J 2
(-73 1500);
DISPLAY 0.872340 (-73 1500);
PAINT GREEN (-73 1500);
DISPLAY INVISIBLE (-73 1500);
FORCEADD TAP..6
R 2
(-75 1650);
FORCEPROP 3 LASTPIN (-125 1650) SIG_NAME M_B_DQ<11>
J 0
(-115 1660);
DISPLAY 0.659574 (-115 1660);
PAINT MONO (-115 1660);
DISPLAY INVISIBLE (-115 1660);
FORCEPROP 1 LASTPIN (-125 1650) BN 11
J 2
(-75 1660);
DISPLAY 0.617021 (-75 1660);
PAINT PINK (-75 1660);
FORCEPROP 2 LAST CDS_LIB mstr_standard
J 2
(-75 1650);
DISPLAY 0.787234 (-75 1650);
PAINT MONO (-75 1650);
DISPLAY INVISIBLE (-75 1650);
FORCEPROP 1 LAST BODY_TYPE PLUMBING
J 2
(-75 1600);
DISPLAY 1.234043 (-75 1600);
PAINT GREEN (-75 1600);
DISPLAY INVISIBLE (-75 1600);
FORCEPROP 1 LAST HDL_TAP TRUE
J 2
(-400 1525);
DISPLAY 1.234043 (-400 1525);
PAINT GREEN (-400 1525);
DISPLAY INVISIBLE (-400 1525);
FORCEPROP 1 LAST PATH I65
J 2
(-73 1650);
DISPLAY 0.872340 (-73 1650);
PAINT GREEN (-73 1650);
DISPLAY INVISIBLE (-73 1650);
FORCEADD TAP..6
R 2
(-75 1600);
FORCEPROP 3 LASTPIN (-125 1600) SIG_NAME M_B_DQ<10>
J 0
(-115 1610);
DISPLAY 0.659574 (-115 1610);
PAINT MONO (-115 1610);
DISPLAY INVISIBLE (-115 1610);
FORCEPROP 1 LASTPIN (-125 1600) BN 10
J 2
(-75 1610);
DISPLAY 0.617021 (-75 1610);
PAINT PINK (-75 1610);
FORCEPROP 2 LAST CDS_LIB mstr_standard
J 2
(-75 1600);
DISPLAY 0.787234 (-75 1600);
PAINT MONO (-75 1600);
DISPLAY INVISIBLE (-75 1600);
FORCEPROP 1 LAST BODY_TYPE PLUMBING
J 2
(-75 1550);
DISPLAY 1.234043 (-75 1550);
PAINT GREEN (-75 1550);
DISPLAY INVISIBLE (-75 1550);
FORCEPROP 1 LAST HDL_TAP TRUE
J 2
(-400 1475);
DISPLAY 1.234043 (-400 1475);
PAINT GREEN (-400 1475);
DISPLAY INVISIBLE (-400 1475);
FORCEPROP 1 LAST PATH I66
J 2
(-73 1600);
DISPLAY 0.872340 (-73 1600);
PAINT GREEN (-73 1600);
DISPLAY INVISIBLE (-73 1600);
FORCEADD SCONN288_H44441003..4
(1675 1650);
FORCEPROP 1 LAST LOCATION J6U1
J 0
(1225 2750);
DISPLAY 0.617021 (1225 2750);
PAINT AQUA (1225 2750);
FORCEPROP 1 LAST PART_NUMBER H44441-003
J 0
(1225 600);
DISPLAY 0.617021 (1225 600);
PAINT BLUE (1225 600);
FORCEPROP 1 LAST MATERIAL SCONN
J 0
(1225 2700);
DISPLAY 0.617021 (1225 2700);
PAINT SKYBLUE (1225 2700);
FORCEPROP 2 LASTPIN (1175 2200) $PN 77
J 2
(1165 2210);
DISPLAY 0.617021 (1165 2210);
PAINT ORANGE (1165 2210);
FORCEPROP 2 LASTPIN (1175 2150) $PN 221
J 2
(1165 2160);
DISPLAY 0.617021 (1165 2160);
PAINT ORANGE (1165 2160);
FORCEPROP 2 LASTPIN (1175 2500) $PN 142
J 2
(1165 2510);
DISPLAY 0.617021 (1165 2510);
PAINT ORANGE (1165 2510);
FORCEPROP 2 LASTPIN (1175 2450) $PN 143
J 2
(1165 2460);
DISPLAY 0.617021 (1165 2460);
PAINT ORANGE (1165 2460);
FORCEPROP 2 LASTPIN (1175 2400) $PN 288
J 2
(1165 2410);
DISPLAY 0.617021 (1165 2410);
PAINT ORANGE (1165 2410);
FORCEPROP 2 LASTPIN (1175 2350) $PN 286
J 2
(1165 2360);
DISPLAY 0.617021 (1165 2360);
PAINT ORANGE (1165 2360);
FORCEPROP 2 LASTPIN (1175 2300) $PN 287
J 2
(1165 2310);
DISPLAY 0.617021 (1165 2310);
PAINT ORANGE (1165 2310);
FORCEPROP 2 LASTPIN (1175 2050) $PN 59
J 2
(1165 2060);
DISPLAY 0.617021 (1165 2060);
PAINT ORANGE (1165 2060);
FORCEPROP 2 LASTPIN (1175 2000) $PN 61
J 2
(1165 2010);
DISPLAY 0.617021 (1165 2010);
PAINT ORANGE (1165 2010);
FORCEPROP 2 LASTPIN (1175 1950) $PN 64
J 2
(1165 1960);
DISPLAY 0.617021 (1165 1960);
PAINT ORANGE (1165 1960);
FORCEPROP 2 LASTPIN (1175 1900) $PN 67
J 2
(1165 1910);
DISPLAY 0.617021 (1165 1910);
PAINT ORANGE (1165 1910);
FORCEPROP 2 LASTPIN (1175 1850) $PN 70
J 2
(1165 1860);
DISPLAY 0.617021 (1165 1860);
PAINT ORANGE (1165 1860);
FORCEPROP 2 LASTPIN (1175 1800) $PN 73
J 2
(1165 1810);
DISPLAY 0.617021 (1165 1810);
PAINT ORANGE (1165 1810);
FORCEPROP 2 LASTPIN (1175 1750) $PN 76
J 2
(1165 1760);
DISPLAY 0.617021 (1165 1760);
PAINT ORANGE (1165 1760);
FORCEPROP 2 LASTPIN (1175 1700) $PN 80
J 2
(1165 1710);
DISPLAY 0.617021 (1165 1710);
PAINT ORANGE (1165 1710);
FORCEPROP 2 LASTPIN (1175 1650) $PN 83
J 2
(1165 1660);
DISPLAY 0.617021 (1165 1660);
PAINT ORANGE (1165 1660);
FORCEPROP 2 LASTPIN (1175 1600) $PN 85
J 2
(1165 1610);
DISPLAY 0.617021 (1165 1610);
PAINT ORANGE (1165 1610);
FORCEPROP 2 LASTPIN (1175 1550) $PN 88
J 2
(1165 1560);
DISPLAY 0.617021 (1165 1560);
PAINT ORANGE (1165 1560);
FORCEPROP 2 LASTPIN (1175 1500) $PN 90
J 2
(1165 1510);
DISPLAY 0.617021 (1165 1510);
PAINT ORANGE (1165 1510);
FORCEPROP 2 LASTPIN (1175 1450) $PN 92
J 2
(1165 1460);
DISPLAY 0.617021 (1165 1460);
PAINT ORANGE (1165 1460);
FORCEPROP 2 LASTPIN (1175 1400) $PN 204
J 2
(1165 1410);
DISPLAY 0.617021 (1165 1410);
PAINT ORANGE (1165 1410);
FORCEPROP 2 LASTPIN (1175 1350) $PN 206
J 2
(1165 1360);
DISPLAY 0.617021 (1165 1360);
PAINT ORANGE (1165 1360);
FORCEPROP 2 LASTPIN (1175 1300) $PN 209
J 2
(1165 1310);
DISPLAY 0.617021 (1165 1310);
PAINT ORANGE (1165 1310);
FORCEPROP 2 LASTPIN (1175 1250) $PN 212
J 2
(1165 1260);
DISPLAY 0.617021 (1165 1260);
PAINT ORANGE (1165 1260);
FORCEPROP 2 LASTPIN (1175 1200) $PN 215
J 2
(1165 1210);
DISPLAY 0.617021 (1165 1210);
PAINT ORANGE (1165 1210);
FORCEPROP 2 LASTPIN (1175 1150) $PN 217
J 2
(1165 1160);
DISPLAY 0.617021 (1165 1160);
PAINT ORANGE (1165 1160);
FORCEPROP 2 LASTPIN (1175 1100) $PN 220
J 2
(1165 1110);
DISPLAY 0.617021 (1165 1110);
PAINT ORANGE (1165 1110);
FORCEPROP 2 LASTPIN (1175 1050) $PN 223
J 2
(1165 1060);
DISPLAY 0.617021 (1165 1060);
PAINT ORANGE (1165 1060);
FORCEPROP 2 LASTPIN (1175 1000) $PN 226
J 2
(1165 1010);
DISPLAY 0.617021 (1165 1010);
PAINT ORANGE (1165 1010);
FORCEPROP 2 LASTPIN (1175 950) $PN 229
J 2
(1165 960);
DISPLAY 0.617021 (1165 960);
PAINT ORANGE (1165 960);
FORCEPROP 2 LASTPIN (1175 900) $PN 231
J 2
(1165 910);
DISPLAY 0.617021 (1165 910);
PAINT ORANGE (1165 910);
FORCEPROP 2 LASTPIN (1175 850) $PN 233
J 2
(1165 860);
DISPLAY 0.617021 (1165 860);
PAINT ORANGE (1165 860);
FORCEPROP 2 LASTPIN (1175 800) $PN 236
J 2
(1165 810);
DISPLAY 0.617021 (1165 810);
PAINT ORANGE (1165 810);
FORCEPROP 2 LASTPIN (2175 2500) $PN 1
J 0
(2185 2510);
DISPLAY 0.617021 (2185 2510);
PAINT ORANGE (2185 2510);
FORCEPROP 2 LASTPIN (2175 2450) $PN 145
J 0
(2185 2460);
DISPLAY 0.617021 (2185 2460);
PAINT ORANGE (2185 2460);
FORCEPROP 1 LAST PACK_TYPE PIP
J 0
(1225 2800);
PAINT SKYBLUE (1225 2800);
DISPLAY INVISIBLE (1225 2800);
FORCEPROP 2 LAST BOM_COST MEM
J 0
(1675 1650);
PAINT ORANGE (1675 1650);
DISPLAY INVISIBLE (1675 1650);
FORCEPROP 2 LAST CDS_LIB mstr_sconn
J 0
(1675 1650);
PAINT ORANGE (1675 1650);
DISPLAY INVISIBLE (1675 1650);
FORCEPROP 2 LAST SEC_TYPE PIP
J 0
(1225 2800);
DISPLAY 1.021277 (1225 2800);
PAINT ORANGE (1225 2800);
DISPLAY INVISIBLE (1225 2800);
FORCEPROP 2 LAST SEC 4
J 0
(1225 2800);
DISPLAY 0.680851 (1225 2800);
PAINT MONO (1225 2800);
DISPLAY INVISIBLE (1225 2800);
FORCEPROP 2 LAST CDS_LOCATION J6U1
J 0
(1225 2750);
DISPLAY 0.617021 (1225 2750);
PAINT AQUA (1225 2750);
DISPLAY INVISIBLE (1225 2750);
FORCEPROP 1 LAST PATH I67
J 0
(1675 2700);
PAINT GREEN (1675 2700);
DISPLAY INVISIBLE (1675 2700);
FORCEPROP 2 LAST ROOM DDR4_CH_B
J 0
(1675 1650);
PAINT ORANGE (1675 1650);
DISPLAY INVISIBLE (1675 1650);
FORCEADD TAP..6
R 2
(-75 1700);
FORCEPROP 3 LASTPIN (-125 1700) SIG_NAME M_B_DQ<12>
J 0
(-115 1710);
DISPLAY 0.659574 (-115 1710);
PAINT MONO (-115 1710);
DISPLAY INVISIBLE (-115 1710);
FORCEPROP 1 LASTPIN (-125 1700) BN 12
J 2
(-75 1710);
DISPLAY 0.617021 (-75 1710);
PAINT PINK (-75 1710);
FORCEPROP 2 LAST CDS_LIB mstr_standard
J 2
(-75 1700);
DISPLAY 0.787234 (-75 1700);
PAINT MONO (-75 1700);
DISPLAY INVISIBLE (-75 1700);
FORCEPROP 1 LAST BODY_TYPE PLUMBING
J 2
(-75 1650);
DISPLAY 1.234043 (-75 1650);
PAINT GREEN (-75 1650);
DISPLAY INVISIBLE (-75 1650);
FORCEPROP 1 LAST HDL_TAP TRUE
J 2
(-400 1575);
DISPLAY 1.234043 (-400 1575);
PAINT GREEN (-400 1575);
DISPLAY INVISIBLE (-400 1575);
FORCEPROP 1 LAST PATH I68
J 2
(-73 1700);
DISPLAY 0.872340 (-73 1700);
PAINT GREEN (-73 1700);
DISPLAY INVISIBLE (-73 1700);
FORCEADD TAP..6
R 2
(-75 1800);
FORCEPROP 3 LASTPIN (-125 1800) SIG_NAME M_B_DQ<14>
J 0
(-115 1810);
DISPLAY 0.659574 (-115 1810);
PAINT MONO (-115 1810);
DISPLAY INVISIBLE (-115 1810);
FORCEPROP 1 LASTPIN (-125 1800) BN 14
J 2
(-75 1810);
DISPLAY 0.617021 (-75 1810);
PAINT PINK (-75 1810);
FORCEPROP 2 LAST CDS_LIB mstr_standard
J 2
(-75 1800);
DISPLAY 0.787234 (-75 1800);
PAINT MONO (-75 1800);
DISPLAY INVISIBLE (-75 1800);
FORCEPROP 1 LAST BODY_TYPE PLUMBING
J 2
(-75 1750);
DISPLAY 1.234043 (-75 1750);
PAINT GREEN (-75 1750);
DISPLAY INVISIBLE (-75 1750);
FORCEPROP 1 LAST HDL_TAP TRUE
J 2
(-400 1675);
DISPLAY 1.234043 (-400 1675);
PAINT GREEN (-400 1675);
DISPLAY INVISIBLE (-400 1675);
FORCEPROP 1 LAST PATH I69
J 2
(-73 1800);
DISPLAY 0.872340 (-73 1800);
PAINT GREEN (-73 1800);
DISPLAY INVISIBLE (-73 1800);
FORCEADD OFFPAGE..1
(-2375 1550);
FORCEPROP 2 LAST $XR0 24 
J 0
(-2626 1550);
DISPLAY 0.638298 (-2626 1550);
PAINT MONO (-2626 1550);
FORCEPROP 2 LAST $XR1 45 
J 0
(-2716 1550);
DISPLAY 0.638298 (-2716 1550);
PAINT MONO (-2716 1550);
FORCEPROP 2 LAST CDS_LIB mstr_standard
J 0
(-2375 1550);
DISPLAY 0.787234 (-2375 1550);
PAINT MONO (-2375 1550);
DISPLAY INVISIBLE (-2375 1550);
FORCEPROP 1 LAST OFFPAGE TRUE
J 0
(-2050 1425);
DISPLAY 0.936170 (-2050 1425);
PAINT GREEN (-2050 1425);
DISPLAY INVISIBLE (-2050 1425);
FORCEPROP 1 LAST COMMENT_BODY TRUE
J 0
(-2250 1450);
DISPLAY 0.936170 (-2250 1450);
PAINT GREEN (-2250 1450);
DISPLAY INVISIBLE (-2250 1450);
FORCEPROP 2 LAST PATH I7
J 0
(-2575 1600);
DISPLAY 1.021277 (-2575 1600);
PAINT ORANGE (-2575 1600);
DISPLAY INVISIBLE (-2575 1600);
FORCEADD TAP..6
R 2
(-75 1750);
FORCEPROP 3 LASTPIN (-125 1750) SIG_NAME M_B_DQ<13>
J 0
(-115 1760);
DISPLAY 0.659574 (-115 1760);
PAINT MONO (-115 1760);
DISPLAY INVISIBLE (-115 1760);
FORCEPROP 1 LASTPIN (-125 1750) BN 13
J 2
(-75 1760);
DISPLAY 0.617021 (-75 1760);
PAINT PINK (-75 1760);
FORCEPROP 2 LAST CDS_LIB mstr_standard
J 2
(-75 1750);
DISPLAY 0.787234 (-75 1750);
PAINT MONO (-75 1750);
DISPLAY INVISIBLE (-75 1750);
FORCEPROP 1 LAST BODY_TYPE PLUMBING
J 2
(-75 1700);
DISPLAY 1.234043 (-75 1700);
PAINT GREEN (-75 1700);
DISPLAY INVISIBLE (-75 1700);
FORCEPROP 1 LAST HDL_TAP TRUE
J 2
(-400 1625);
DISPLAY 1.234043 (-400 1625);
PAINT GREEN (-400 1625);
DISPLAY INVISIBLE (-400 1625);
FORCEPROP 1 LAST PATH I70
J 2
(-73 1750);
DISPLAY 0.872340 (-73 1750);
PAINT GREEN (-73 1750);
DISPLAY INVISIBLE (-73 1750);
FORCEADD TAP..6
R 2
(-75 1900);
FORCEPROP 3 LASTPIN (-125 1900) SIG_NAME M_B_DQ<16>
J 0
(-115 1910);
DISPLAY 0.659574 (-115 1910);
PAINT MONO (-115 1910);
DISPLAY INVISIBLE (-115 1910);
FORCEPROP 1 LASTPIN (-125 1900) BN 16
J 2
(-75 1910);
DISPLAY 0.617021 (-75 1910);
PAINT PINK (-75 1910);
FORCEPROP 2 LAST CDS_LIB mstr_standard
J 2
(-75 1900);
DISPLAY 0.787234 (-75 1900);
PAINT MONO (-75 1900);
DISPLAY INVISIBLE (-75 1900);
FORCEPROP 1 LAST BODY_TYPE PLUMBING
J 2
(-75 1850);
DISPLAY 1.234043 (-75 1850);
PAINT GREEN (-75 1850);
DISPLAY INVISIBLE (-75 1850);
FORCEPROP 1 LAST HDL_TAP TRUE
J 2
(-400 1775);
DISPLAY 1.234043 (-400 1775);
PAINT GREEN (-400 1775);
DISPLAY INVISIBLE (-400 1775);
FORCEPROP 1 LAST PATH I71
J 2
(-73 1900);
DISPLAY 0.872340 (-73 1900);
PAINT GREEN (-73 1900);
DISPLAY INVISIBLE (-73 1900);
FORCEADD TAP..6
R 2
(-75 1850);
FORCEPROP 3 LASTPIN (-125 1850) SIG_NAME M_B_DQ<15>
J 0
(-115 1860);
DISPLAY 0.659574 (-115 1860);
PAINT MONO (-115 1860);
DISPLAY INVISIBLE (-115 1860);
FORCEPROP 1 LASTPIN (-125 1850) BN 15
J 2
(-75 1860);
DISPLAY 0.617021 (-75 1860);
PAINT PINK (-75 1860);
FORCEPROP 2 LAST CDS_LIB mstr_standard
J 2
(-75 1850);
DISPLAY 0.787234 (-75 1850);
PAINT MONO (-75 1850);
DISPLAY INVISIBLE (-75 1850);
FORCEPROP 1 LAST BODY_TYPE PLUMBING
J 2
(-75 1800);
DISPLAY 1.234043 (-75 1800);
PAINT GREEN (-75 1800);
DISPLAY INVISIBLE (-75 1800);
FORCEPROP 1 LAST HDL_TAP TRUE
J 2
(-400 1725);
DISPLAY 1.234043 (-400 1725);
PAINT GREEN (-400 1725);
DISPLAY INVISIBLE (-400 1725);
FORCEPROP 1 LAST PATH I72
J 2
(-73 1850);
DISPLAY 0.872340 (-73 1850);
PAINT GREEN (-73 1850);
DISPLAY INVISIBLE (-73 1850);
FORCEADD TAP..6
R 2
(-75 1950);
FORCEPROP 3 LASTPIN (-125 1950) SIG_NAME M_B_DQ<17>
J 0
(-115 1960);
DISPLAY 0.659574 (-115 1960);
PAINT MONO (-115 1960);
DISPLAY INVISIBLE (-115 1960);
FORCEPROP 1 LASTPIN (-125 1950) BN 17
J 2
(-75 1960);
DISPLAY 0.617021 (-75 1960);
PAINT PINK (-75 1960);
FORCEPROP 2 LAST CDS_LIB mstr_standard
J 2
(-75 1950);
DISPLAY 0.787234 (-75 1950);
PAINT MONO (-75 1950);
DISPLAY INVISIBLE (-75 1950);
FORCEPROP 1 LAST BODY_TYPE PLUMBING
J 2
(-75 1900);
DISPLAY 1.234043 (-75 1900);
PAINT GREEN (-75 1900);
DISPLAY INVISIBLE (-75 1900);
FORCEPROP 1 LAST HDL_TAP TRUE
J 2
(-400 1825);
DISPLAY 1.234043 (-400 1825);
PAINT GREEN (-400 1825);
DISPLAY INVISIBLE (-400 1825);
FORCEPROP 1 LAST PATH I73
J 2
(-73 1950);
DISPLAY 0.872340 (-73 1950);
PAINT GREEN (-73 1950);
DISPLAY INVISIBLE (-73 1950);
FORCEADD TAP..6
R 2
(-75 2000);
FORCEPROP 3 LASTPIN (-125 2000) SIG_NAME M_B_DQ<18>
J 0
(-115 2010);
DISPLAY 0.659574 (-115 2010);
PAINT MONO (-115 2010);
DISPLAY INVISIBLE (-115 2010);
FORCEPROP 1 LASTPIN (-125 2000) BN 18
J 2
(-75 2010);
DISPLAY 0.617021 (-75 2010);
PAINT PINK (-75 2010);
FORCEPROP 2 LAST CDS_LIB mstr_standard
J 2
(-75 2000);
DISPLAY 0.787234 (-75 2000);
PAINT MONO (-75 2000);
DISPLAY INVISIBLE (-75 2000);
FORCEPROP 1 LAST BODY_TYPE PLUMBING
J 2
(-75 1950);
DISPLAY 1.234043 (-75 1950);
PAINT GREEN (-75 1950);
DISPLAY INVISIBLE (-75 1950);
FORCEPROP 1 LAST HDL_TAP TRUE
J 2
(-400 1875);
DISPLAY 1.234043 (-400 1875);
PAINT GREEN (-400 1875);
DISPLAY INVISIBLE (-400 1875);
FORCEPROP 1 LAST PATH I74
J 2
(-73 2000);
DISPLAY 0.872340 (-73 2000);
PAINT GREEN (-73 2000);
DISPLAY INVISIBLE (-73 2000);
FORCEADD TAP..6
R 2
(-75 2050);
FORCEPROP 3 LASTPIN (-125 2050) SIG_NAME M_B_DQ<19>
J 0
(-115 2060);
DISPLAY 0.659574 (-115 2060);
PAINT MONO (-115 2060);
DISPLAY INVISIBLE (-115 2060);
FORCEPROP 1 LASTPIN (-125 2050) BN 19
J 2
(-75 2060);
DISPLAY 0.617021 (-75 2060);
PAINT PINK (-75 2060);
FORCEPROP 2 LAST CDS_LIB mstr_standard
J 2
(-75 2050);
DISPLAY 0.787234 (-75 2050);
PAINT MONO (-75 2050);
DISPLAY INVISIBLE (-75 2050);
FORCEPROP 1 LAST BODY_TYPE PLUMBING
J 2
(-75 2000);
DISPLAY 1.234043 (-75 2000);
PAINT GREEN (-75 2000);
DISPLAY INVISIBLE (-75 2000);
FORCEPROP 1 LAST HDL_TAP TRUE
J 2
(-400 1925);
DISPLAY 1.234043 (-400 1925);
PAINT GREEN (-400 1925);
DISPLAY INVISIBLE (-400 1925);
FORCEPROP 1 LAST PATH I75
J 2
(-73 2050);
DISPLAY 0.872340 (-73 2050);
PAINT GREEN (-73 2050);
DISPLAY INVISIBLE (-73 2050);
FORCEADD TAP..6
R 2
(-75 2100);
FORCEPROP 3 LASTPIN (-125 2100) SIG_NAME M_B_DQ<20>
J 0
(-115 2110);
DISPLAY 0.659574 (-115 2110);
PAINT MONO (-115 2110);
DISPLAY INVISIBLE (-115 2110);
FORCEPROP 1 LASTPIN (-125 2100) BN 20
J 2
(-75 2110);
DISPLAY 0.617021 (-75 2110);
PAINT PINK (-75 2110);
FORCEPROP 2 LAST CDS_LIB mstr_standard
J 2
(-75 2100);
DISPLAY 0.787234 (-75 2100);
PAINT MONO (-75 2100);
DISPLAY INVISIBLE (-75 2100);
FORCEPROP 1 LAST BODY_TYPE PLUMBING
J 2
(-75 2050);
DISPLAY 1.234043 (-75 2050);
PAINT GREEN (-75 2050);
DISPLAY INVISIBLE (-75 2050);
FORCEPROP 1 LAST HDL_TAP TRUE
J 2
(-400 1975);
DISPLAY 1.234043 (-400 1975);
PAINT GREEN (-400 1975);
DISPLAY INVISIBLE (-400 1975);
FORCEPROP 1 LAST PATH I76
J 2
(-73 2100);
DISPLAY 0.872340 (-73 2100);
PAINT GREEN (-73 2100);
DISPLAY INVISIBLE (-73 2100);
FORCEADD TAP..6
R 2
(-75 2200);
FORCEPROP 3 LASTPIN (-125 2200) SIG_NAME M_B_DQ<22>
J 0
(-115 2210);
DISPLAY 0.659574 (-115 2210);
PAINT MONO (-115 2210);
DISPLAY INVISIBLE (-115 2210);
FORCEPROP 1 LASTPIN (-125 2200) BN 22
J 2
(-75 2210);
DISPLAY 0.617021 (-75 2210);
PAINT PINK (-75 2210);
FORCEPROP 2 LAST CDS_LIB mstr_standard
J 2
(-75 2200);
DISPLAY 0.787234 (-75 2200);
PAINT MONO (-75 2200);
DISPLAY INVISIBLE (-75 2200);
FORCEPROP 1 LAST BODY_TYPE PLUMBING
J 2
(-75 2150);
DISPLAY 1.234043 (-75 2150);
PAINT GREEN (-75 2150);
DISPLAY INVISIBLE (-75 2150);
FORCEPROP 1 LAST HDL_TAP TRUE
J 2
(-400 2075);
DISPLAY 1.234043 (-400 2075);
PAINT GREEN (-400 2075);
DISPLAY INVISIBLE (-400 2075);
FORCEPROP 1 LAST PATH I77
J 2
(-73 2200);
DISPLAY 0.872340 (-73 2200);
PAINT GREEN (-73 2200);
DISPLAY INVISIBLE (-73 2200);
FORCEADD TAP..6
R 2
(-75 2150);
FORCEPROP 3 LASTPIN (-125 2150) SIG_NAME M_B_DQ<21>
J 0
(-115 2160);
DISPLAY 0.659574 (-115 2160);
PAINT MONO (-115 2160);
DISPLAY INVISIBLE (-115 2160);
FORCEPROP 1 LASTPIN (-125 2150) BN 21
J 2
(-75 2160);
DISPLAY 0.617021 (-75 2160);
PAINT PINK (-75 2160);
FORCEPROP 2 LAST CDS_LIB mstr_standard
J 2
(-75 2150);
DISPLAY 0.787234 (-75 2150);
PAINT MONO (-75 2150);
DISPLAY INVISIBLE (-75 2150);
FORCEPROP 1 LAST BODY_TYPE PLUMBING
J 2
(-75 2100);
DISPLAY 1.234043 (-75 2100);
PAINT GREEN (-75 2100);
DISPLAY INVISIBLE (-75 2100);
FORCEPROP 1 LAST HDL_TAP TRUE
J 2
(-400 2025);
DISPLAY 1.234043 (-400 2025);
PAINT GREEN (-400 2025);
DISPLAY INVISIBLE (-400 2025);
FORCEPROP 1 LAST PATH I78
J 2
(-73 2150);
DISPLAY 0.872340 (-73 2150);
PAINT GREEN (-73 2150);
DISPLAY INVISIBLE (-73 2150);
FORCEADD TAP..6
R 2
(-75 2250);
FORCEPROP 3 LASTPIN (-125 2250) SIG_NAME M_B_DQ<23>
J 0
(-115 2260);
DISPLAY 0.659574 (-115 2260);
PAINT MONO (-115 2260);
DISPLAY INVISIBLE (-115 2260);
FORCEPROP 1 LASTPIN (-125 2250) BN 23
J 2
(-75 2260);
DISPLAY 0.617021 (-75 2260);
PAINT PINK (-75 2260);
FORCEPROP 2 LAST CDS_LIB mstr_standard
J 2
(-75 2250);
DISPLAY 0.787234 (-75 2250);
PAINT MONO (-75 2250);
DISPLAY INVISIBLE (-75 2250);
FORCEPROP 1 LAST BODY_TYPE PLUMBING
J 2
(-75 2200);
DISPLAY 1.234043 (-75 2200);
PAINT GREEN (-75 2200);
DISPLAY INVISIBLE (-75 2200);
FORCEPROP 1 LAST HDL_TAP TRUE
J 2
(-400 2125);
DISPLAY 1.234043 (-400 2125);
PAINT GREEN (-400 2125);
DISPLAY INVISIBLE (-400 2125);
FORCEPROP 1 LAST PATH I79
J 2
(-73 2250);
DISPLAY 0.872340 (-73 2250);
PAINT GREEN (-73 2250);
DISPLAY INVISIBLE (-73 2250);
FORCEADD OFFPAGE..5
(-2550 1950);
FORCEPROP 2 LAST $XR0 43 
J 0
(-2804 1950);
DISPLAY 0.638298 (-2804 1950);
PAINT MONO (-2804 1950);
FORCEPROP 2 LAST $XR1 44 
J 0
(-2894 1950);
DISPLAY 0.638298 (-2894 1950);
PAINT MONO (-2894 1950);
FORCEPROP 2 LAST $XR2 45 
J 0
(-2984 1950);
DISPLAY 0.638298 (-2984 1950);
PAINT MONO (-2984 1950);
FORCEPROP 2 LAST $XR3 47 
J 0
(-3074 1950);
DISPLAY 0.638298 (-3074 1950);
PAINT MONO (-3074 1950);
FORCEPROP 2 LAST $XR4 48 
J 0
(-3164 1950);
DISPLAY 0.638298 (-3164 1950);
PAINT MONO (-3164 1950);
FORCEPROP 2 LAST $XR5 49 
J 0
(-3254 1950);
DISPLAY 0.638298 (-3254 1950);
PAINT MONO (-3254 1950);
FORCEPROP 2 LAST $XR6 50 
J 0
(-3344 1950);
DISPLAY 0.638298 (-3344 1950);
PAINT MONO (-3344 1950);
FORCEPROP 2 LAST $XR7 51 
J 0
(-3434 1950);
DISPLAY 0.638298 (-3434 1950);
PAINT MONO (-3434 1950);
FORCEPROP 2 LAST $XR8 52 
J 0
(-3524 1950);
DISPLAY 0.638298 (-3524 1950);
PAINT MONO (-3524 1950);
FORCEPROP 2 LAST $XR9 53 
J 0
(-3614 1950);
DISPLAY 0.638298 (-3614 1950);
PAINT MONO (-3614 1950);
FORCEPROP 2 LAST $XR10 54 
J 0
(-2804 1914);
DISPLAY 0.638298 (-2804 1914);
PAINT MONO (-2804 1914);
FORCEPROP 2 LAST $XR11 77 
J 0
(-2894 1914);
DISPLAY 0.638298 (-2894 1914);
PAINT MONO (-2894 1914);
FORCEPROP 2 LAST $XR12 78 
J 0
(-2984 1914);
DISPLAY 0.638298 (-2984 1914);
PAINT MONO (-2984 1914);
FORCEPROP 2 LAST $XR13 79 
J 0
(-3074 1914);
DISPLAY 0.638298 (-3074 1914);
PAINT MONO (-3074 1914);
FORCEPROP 2 LAST $XR14 80 
J 0
(-3164 1914);
DISPLAY 0.638298 (-3164 1914);
PAINT MONO (-3164 1914);
FORCEPROP 2 LAST $XR15 81 
J 0
(-3254 1914);
DISPLAY 0.638298 (-3254 1914);
PAINT MONO (-3254 1914);
FORCEPROP 2 LAST $XR16 82 
J 0
(-3344 1914);
DISPLAY 0.638298 (-3344 1914);
PAINT MONO (-3344 1914);
FORCEPROP 2 LAST $XR17 83 
J 0
(-3434 1914);
DISPLAY 0.638298 (-3434 1914);
PAINT MONO (-3434 1914);
FORCEPROP 2 LAST $XR18 84 
J 0
(-3524 1914);
DISPLAY 0.638298 (-3524 1914);
PAINT MONO (-3524 1914);
FORCEPROP 2 LAST $XR19 85 
J 0
(-2804 1986);
DISPLAY 0.638298 (-2804 1986);
PAINT MONO (-2804 1986);
FORCEPROP 2 LAST $XR20 86 
J 0
(-2894 1986);
DISPLAY 0.638298 (-2894 1986);
PAINT MONO (-2894 1986);
FORCEPROP 2 LAST $XR21 87 
J 0
(-2984 1986);
DISPLAY 0.638298 (-2984 1986);
PAINT MONO (-2984 1986);
FORCEPROP 2 LAST $XR22 88 
J 0
(-3074 1986);
DISPLAY 0.638298 (-3074 1986);
PAINT MONO (-3074 1986);
FORCEPROP 2 LAST $XR23 94 
J 0
(-3164 1986);
DISPLAY 0.638298 (-3164 1986);
PAINT MONO (-3164 1986);
FORCEPROP 2 LAST CDS_LIB mstr_standard
J 0
(-2550 1950);
DISPLAY 0.787234 (-2550 1950);
PAINT MONO (-2550 1950);
DISPLAY INVISIBLE (-2550 1950);
FORCEPROP 1 LAST OFFPAGE TRUE
J 0
(-2225 1825);
DISPLAY 1.404255 (-2225 1825);
PAINT GREEN (-2225 1825);
DISPLAY INVISIBLE (-2225 1825);
FORCEPROP 1 LAST COMMENT_BODY TRUE
J 0
(-2450 1875);
DISPLAY 1.404255 (-2450 1875);
PAINT GREEN (-2450 1875);
DISPLAY INVISIBLE (-2450 1875);
FORCEPROP 2 LAST PATH I8
J 0
(-2800 2000);
DISPLAY 1.021277 (-2800 2000);
PAINT ORANGE (-2800 2000);
DISPLAY INVISIBLE (-2800 2000);
FORCEADD TAP..6
R 2
(-75 2300);
FORCEPROP 3 LASTPIN (-125 2300) SIG_NAME M_B_DQ<24>
J 0
(-115 2310);
DISPLAY 0.659574 (-115 2310);
PAINT MONO (-115 2310);
DISPLAY INVISIBLE (-115 2310);
FORCEPROP 1 LASTPIN (-125 2300) BN 24
J 2
(-75 2310);
DISPLAY 0.617021 (-75 2310);
PAINT PINK (-75 2310);
FORCEPROP 2 LAST CDS_LIB mstr_standard
J 2
(-75 2300);
DISPLAY 0.787234 (-75 2300);
PAINT MONO (-75 2300);
DISPLAY INVISIBLE (-75 2300);
FORCEPROP 1 LAST BODY_TYPE PLUMBING
J 2
(-75 2250);
DISPLAY 1.234043 (-75 2250);
PAINT GREEN (-75 2250);
DISPLAY INVISIBLE (-75 2250);
FORCEPROP 1 LAST HDL_TAP TRUE
J 2
(-400 2175);
DISPLAY 1.234043 (-400 2175);
PAINT GREEN (-400 2175);
DISPLAY INVISIBLE (-400 2175);
FORCEPROP 1 LAST PATH I80
J 2
(-73 2300);
DISPLAY 0.872340 (-73 2300);
PAINT GREEN (-73 2300);
DISPLAY INVISIBLE (-73 2300);
FORCEADD TAP..6
R 2
(-75 2350);
FORCEPROP 3 LASTPIN (-125 2350) SIG_NAME M_B_DQ<25>
J 0
(-115 2360);
DISPLAY 0.659574 (-115 2360);
PAINT MONO (-115 2360);
DISPLAY INVISIBLE (-115 2360);
FORCEPROP 1 LASTPIN (-125 2350) BN 25
J 2
(-75 2360);
DISPLAY 0.617021 (-75 2360);
PAINT PINK (-75 2360);
FORCEPROP 2 LAST CDS_LIB mstr_standard
J 2
(-75 2350);
DISPLAY 0.787234 (-75 2350);
PAINT MONO (-75 2350);
DISPLAY INVISIBLE (-75 2350);
FORCEPROP 1 LAST BODY_TYPE PLUMBING
J 2
(-75 2300);
DISPLAY 1.234043 (-75 2300);
PAINT GREEN (-75 2300);
DISPLAY INVISIBLE (-75 2300);
FORCEPROP 1 LAST HDL_TAP TRUE
J 2
(-400 2225);
DISPLAY 1.234043 (-400 2225);
PAINT GREEN (-400 2225);
DISPLAY INVISIBLE (-400 2225);
FORCEPROP 1 LAST PATH I81
J 2
(-73 2350);
DISPLAY 0.872340 (-73 2350);
PAINT GREEN (-73 2350);
DISPLAY INVISIBLE (-73 2350);
FORCEADD TAP..6
R 2
(-75 2400);
FORCEPROP 3 LASTPIN (-125 2400) SIG_NAME M_B_DQ<26>
J 0
(-115 2410);
DISPLAY 0.659574 (-115 2410);
PAINT MONO (-115 2410);
DISPLAY INVISIBLE (-115 2410);
FORCEPROP 1 LASTPIN (-125 2400) BN 26
J 2
(-75 2410);
DISPLAY 0.617021 (-75 2410);
PAINT PINK (-75 2410);
FORCEPROP 2 LAST CDS_LIB mstr_standard
J 2
(-75 2400);
DISPLAY 0.787234 (-75 2400);
PAINT MONO (-75 2400);
DISPLAY INVISIBLE (-75 2400);
FORCEPROP 1 LAST BODY_TYPE PLUMBING
J 2
(-75 2350);
DISPLAY 1.234043 (-75 2350);
PAINT GREEN (-75 2350);
DISPLAY INVISIBLE (-75 2350);
FORCEPROP 1 LAST HDL_TAP TRUE
J 2
(-400 2275);
DISPLAY 1.234043 (-400 2275);
PAINT GREEN (-400 2275);
DISPLAY INVISIBLE (-400 2275);
FORCEPROP 1 LAST PATH I82
J 2
(-73 2400);
DISPLAY 0.872340 (-73 2400);
PAINT GREEN (-73 2400);
DISPLAY INVISIBLE (-73 2400);
FORCEADD TAP..6
R 2
(-75 2450);
FORCEPROP 3 LASTPIN (-125 2450) SIG_NAME M_B_DQ<27>
J 0
(-115 2460);
DISPLAY 0.659574 (-115 2460);
PAINT MONO (-115 2460);
DISPLAY INVISIBLE (-115 2460);
FORCEPROP 1 LASTPIN (-125 2450) BN 27
J 2
(-75 2460);
DISPLAY 0.617021 (-75 2460);
PAINT PINK (-75 2460);
FORCEPROP 2 LAST CDS_LIB mstr_standard
J 2
(-75 2450);
DISPLAY 0.787234 (-75 2450);
PAINT MONO (-75 2450);
DISPLAY INVISIBLE (-75 2450);
FORCEPROP 1 LAST BODY_TYPE PLUMBING
J 2
(-75 2400);
DISPLAY 1.234043 (-75 2400);
PAINT GREEN (-75 2400);
DISPLAY INVISIBLE (-75 2400);
FORCEPROP 1 LAST HDL_TAP TRUE
J 2
(-400 2325);
DISPLAY 1.234043 (-400 2325);
PAINT GREEN (-400 2325);
DISPLAY INVISIBLE (-400 2325);
FORCEPROP 1 LAST PATH I83
J 2
(-73 2450);
DISPLAY 0.872340 (-73 2450);
PAINT GREEN (-73 2450);
DISPLAY INVISIBLE (-73 2450);
FORCEADD TAP..6
R 2
(-75 2550);
FORCEPROP 3 LASTPIN (-125 2550) SIG_NAME M_B_DQ<29>
J 0
(-115 2560);
DISPLAY 0.659574 (-115 2560);
PAINT MONO (-115 2560);
DISPLAY INVISIBLE (-115 2560);
FORCEPROP 1 LASTPIN (-125 2550) BN 29
J 2
(-75 2560);
DISPLAY 0.617021 (-75 2560);
PAINT PINK (-75 2560);
FORCEPROP 2 LAST CDS_LIB mstr_standard
J 2
(-75 2550);
DISPLAY 0.787234 (-75 2550);
PAINT MONO (-75 2550);
DISPLAY INVISIBLE (-75 2550);
FORCEPROP 1 LAST BODY_TYPE PLUMBING
J 2
(-75 2500);
DISPLAY 1.234043 (-75 2500);
PAINT GREEN (-75 2500);
DISPLAY INVISIBLE (-75 2500);
FORCEPROP 1 LAST HDL_TAP TRUE
J 2
(-400 2425);
DISPLAY 1.234043 (-400 2425);
PAINT GREEN (-400 2425);
DISPLAY INVISIBLE (-400 2425);
FORCEPROP 1 LAST PATH I84
J 2
(-73 2550);
DISPLAY 0.872340 (-73 2550);
PAINT GREEN (-73 2550);
DISPLAY INVISIBLE (-73 2550);
FORCEADD TAP..6
R 2
(-75 2500);
FORCEPROP 3 LASTPIN (-125 2500) SIG_NAME M_B_DQ<28>
J 0
(-115 2510);
DISPLAY 0.659574 (-115 2510);
PAINT MONO (-115 2510);
DISPLAY INVISIBLE (-115 2510);
FORCEPROP 1 LASTPIN (-125 2500) BN 28
J 2
(-75 2510);
DISPLAY 0.617021 (-75 2510);
PAINT PINK (-75 2510);
FORCEPROP 2 LAST CDS_LIB mstr_standard
J 2
(-75 2500);
DISPLAY 0.787234 (-75 2500);
PAINT MONO (-75 2500);
DISPLAY INVISIBLE (-75 2500);
FORCEPROP 1 LAST BODY_TYPE PLUMBING
J 2
(-75 2450);
DISPLAY 1.234043 (-75 2450);
PAINT GREEN (-75 2450);
DISPLAY INVISIBLE (-75 2450);
FORCEPROP 1 LAST HDL_TAP TRUE
J 2
(-400 2375);
DISPLAY 1.234043 (-400 2375);
PAINT GREEN (-400 2375);
DISPLAY INVISIBLE (-400 2375);
FORCEPROP 1 LAST PATH I85
J 2
(-73 2500);
DISPLAY 0.872340 (-73 2500);
PAINT GREEN (-73 2500);
DISPLAY INVISIBLE (-73 2500);
FORCEADD TAP..6
R 2
(-75 2600);
FORCEPROP 3 LASTPIN (-125 2600) SIG_NAME M_B_DQ<30>
J 0
(-115 2610);
DISPLAY 0.659574 (-115 2610);
PAINT MONO (-115 2610);
DISPLAY INVISIBLE (-115 2610);
FORCEPROP 1 LASTPIN (-125 2600) BN 30
J 2
(-75 2610);
DISPLAY 0.617021 (-75 2610);
PAINT PINK (-75 2610);
FORCEPROP 2 LAST CDS_LIB mstr_standard
J 2
(-75 2600);
DISPLAY 0.787234 (-75 2600);
PAINT MONO (-75 2600);
DISPLAY INVISIBLE (-75 2600);
FORCEPROP 1 LAST BODY_TYPE PLUMBING
J 2
(-75 2550);
DISPLAY 1.234043 (-75 2550);
PAINT GREEN (-75 2550);
DISPLAY INVISIBLE (-75 2550);
FORCEPROP 1 LAST HDL_TAP TRUE
J 2
(-400 2475);
DISPLAY 1.234043 (-400 2475);
PAINT GREEN (-400 2475);
DISPLAY INVISIBLE (-400 2475);
FORCEPROP 1 LAST PATH I86
J 2
(-73 2600);
DISPLAY 0.872340 (-73 2600);
PAINT GREEN (-73 2600);
DISPLAY INVISIBLE (-73 2600);
FORCEADD TAP..6
R 2
(-75 2650);
FORCEPROP 3 LASTPIN (-125 2650) SIG_NAME M_B_DQ<31>
J 0
(-115 2660);
DISPLAY 0.659574 (-115 2660);
PAINT MONO (-115 2660);
DISPLAY INVISIBLE (-115 2660);
FORCEPROP 1 LASTPIN (-125 2650) BN 31
J 2
(-75 2660);
DISPLAY 0.617021 (-75 2660);
PAINT PINK (-75 2660);
FORCEPROP 2 LAST CDS_LIB mstr_standard
J 2
(-75 2650);
DISPLAY 0.787234 (-75 2650);
PAINT MONO (-75 2650);
DISPLAY INVISIBLE (-75 2650);
FORCEPROP 1 LAST BODY_TYPE PLUMBING
J 2
(-75 2600);
DISPLAY 1.234043 (-75 2600);
PAINT GREEN (-75 2600);
DISPLAY INVISIBLE (-75 2600);
FORCEPROP 1 LAST HDL_TAP TRUE
J 2
(-400 2525);
DISPLAY 1.234043 (-400 2525);
PAINT GREEN (-400 2525);
DISPLAY INVISIBLE (-400 2525);
FORCEPROP 1 LAST PATH I87
J 2
(-73 2650);
DISPLAY 0.872340 (-73 2650);
PAINT GREEN (-73 2650);
DISPLAY INVISIBLE (-73 2650);
FORCEADD TAP..6
R 2
(-75 2700);
FORCEPROP 3 LASTPIN (-125 2700) SIG_NAME M_B_DQ<32>
J 0
(-115 2710);
DISPLAY 0.659574 (-115 2710);
PAINT MONO (-115 2710);
DISPLAY INVISIBLE (-115 2710);
FORCEPROP 1 LASTPIN (-125 2700) BN 32
J 2
(-75 2710);
DISPLAY 0.617021 (-75 2710);
PAINT PINK (-75 2710);
FORCEPROP 2 LAST CDS_LIB mstr_standard
J 2
(-75 2700);
DISPLAY 0.787234 (-75 2700);
PAINT MONO (-75 2700);
DISPLAY INVISIBLE (-75 2700);
FORCEPROP 1 LAST BODY_TYPE PLUMBING
J 2
(-75 2650);
DISPLAY 1.234043 (-75 2650);
PAINT GREEN (-75 2650);
DISPLAY INVISIBLE (-75 2650);
FORCEPROP 1 LAST HDL_TAP TRUE
J 2
(-400 2575);
DISPLAY 1.234043 (-400 2575);
PAINT GREEN (-400 2575);
DISPLAY INVISIBLE (-400 2575);
FORCEPROP 1 LAST PATH I88
J 2
(-73 2700);
DISPLAY 0.872340 (-73 2700);
PAINT GREEN (-73 2700);
DISPLAY INVISIBLE (-73 2700);
FORCEADD TAP..6
R 2
(-75 2750);
FORCEPROP 3 LASTPIN (-125 2750) SIG_NAME M_B_DQ<33>
J 0
(-115 2760);
DISPLAY 0.659574 (-115 2760);
PAINT MONO (-115 2760);
DISPLAY INVISIBLE (-115 2760);
FORCEPROP 1 LASTPIN (-125 2750) BN 33
J 2
(-75 2760);
DISPLAY 0.617021 (-75 2760);
PAINT PINK (-75 2760);
FORCEPROP 2 LAST CDS_LIB mstr_standard
J 2
(-75 2750);
DISPLAY 0.787234 (-75 2750);
PAINT MONO (-75 2750);
DISPLAY INVISIBLE (-75 2750);
FORCEPROP 1 LAST BODY_TYPE PLUMBING
J 2
(-75 2700);
DISPLAY 1.234043 (-75 2700);
PAINT GREEN (-75 2700);
DISPLAY INVISIBLE (-75 2700);
FORCEPROP 1 LAST HDL_TAP TRUE
J 2
(-400 2625);
DISPLAY 1.234043 (-400 2625);
PAINT GREEN (-400 2625);
DISPLAY INVISIBLE (-400 2625);
FORCEPROP 1 LAST PATH I89
J 2
(-73 2750);
DISPLAY 0.872340 (-73 2750);
PAINT GREEN (-73 2750);
DISPLAY INVISIBLE (-73 2750);
FORCEADD OFFPAGE..1
(-2375 3150);
FORCEPROP 2 LAST $XR0 24 
J 0
(-2596 3150);
DISPLAY 0.638298 (-2596 3150);
PAINT MONO (-2596 3150);
FORCEPROP 2 LAST $XR1 45 
J 0
(-2686 3150);
DISPLAY 0.638298 (-2686 3150);
PAINT MONO (-2686 3150);
FORCEPROP 2 LAST CDS_LIB mstr_standard
J 0
(-2375 3150);
DISPLAY 0.787234 (-2375 3150);
PAINT MONO (-2375 3150);
DISPLAY INVISIBLE (-2375 3150);
FORCEPROP 1 LAST OFFPAGE TRUE
J 0
(-2050 3025);
DISPLAY 0.936170 (-2050 3025);
PAINT GREEN (-2050 3025);
DISPLAY INVISIBLE (-2050 3025);
FORCEPROP 1 LAST COMMENT_BODY TRUE
J 0
(-2250 3050);
DISPLAY 0.936170 (-2250 3050);
PAINT GREEN (-2250 3050);
DISPLAY INVISIBLE (-2250 3050);
FORCEPROP 2 LAST PATH I9
J 0
(-2575 3200);
DISPLAY 1.021277 (-2575 3200);
PAINT ORANGE (-2575 3200);
DISPLAY INVISIBLE (-2575 3200);
FORCEADD TAP..6
R 2
(-75 2800);
FORCEPROP 3 LASTPIN (-125 2800) SIG_NAME M_B_DQ<34>
J 0
(-115 2810);
DISPLAY 0.659574 (-115 2810);
PAINT MONO (-115 2810);
DISPLAY INVISIBLE (-115 2810);
FORCEPROP 1 LASTPIN (-125 2800) BN 34
J 2
(-75 2810);
DISPLAY 0.617021 (-75 2810);
PAINT PINK (-75 2810);
FORCEPROP 2 LAST CDS_LIB mstr_standard
J 2
(-75 2800);
DISPLAY 0.787234 (-75 2800);
PAINT MONO (-75 2800);
DISPLAY INVISIBLE (-75 2800);
FORCEPROP 1 LAST BODY_TYPE PLUMBING
J 2
(-75 2750);
DISPLAY 1.234043 (-75 2750);
PAINT GREEN (-75 2750);
DISPLAY INVISIBLE (-75 2750);
FORCEPROP 1 LAST HDL_TAP TRUE
J 2
(-400 2675);
DISPLAY 1.234043 (-400 2675);
PAINT GREEN (-400 2675);
DISPLAY INVISIBLE (-400 2675);
FORCEPROP 1 LAST PATH I90
J 2
(-73 2800);
DISPLAY 0.872340 (-73 2800);
PAINT GREEN (-73 2800);
DISPLAY INVISIBLE (-73 2800);
FORCEADD TAP..6
R 2
(-75 2850);
FORCEPROP 3 LASTPIN (-125 2850) SIG_NAME M_B_DQ<35>
J 0
(-115 2860);
DISPLAY 0.659574 (-115 2860);
PAINT MONO (-115 2860);
DISPLAY INVISIBLE (-115 2860);
FORCEPROP 1 LASTPIN (-125 2850) BN 35
J 2
(-75 2860);
DISPLAY 0.617021 (-75 2860);
PAINT PINK (-75 2860);
FORCEPROP 2 LAST CDS_LIB mstr_standard
J 2
(-75 2850);
DISPLAY 0.787234 (-75 2850);
PAINT MONO (-75 2850);
DISPLAY INVISIBLE (-75 2850);
FORCEPROP 1 LAST BODY_TYPE PLUMBING
J 2
(-75 2800);
DISPLAY 1.234043 (-75 2800);
PAINT GREEN (-75 2800);
DISPLAY INVISIBLE (-75 2800);
FORCEPROP 1 LAST HDL_TAP TRUE
J 2
(-400 2725);
DISPLAY 1.234043 (-400 2725);
PAINT GREEN (-400 2725);
DISPLAY INVISIBLE (-400 2725);
FORCEPROP 1 LAST PATH I91
J 2
(-73 2850);
DISPLAY 0.872340 (-73 2850);
PAINT GREEN (-73 2850);
DISPLAY INVISIBLE (-73 2850);
FORCEADD TAP..6
R 2
(-75 2900);
FORCEPROP 3 LASTPIN (-125 2900) SIG_NAME M_B_DQ<36>
J 0
(-115 2910);
DISPLAY 0.659574 (-115 2910);
PAINT MONO (-115 2910);
DISPLAY INVISIBLE (-115 2910);
FORCEPROP 1 LASTPIN (-125 2900) BN 36
J 2
(-75 2910);
DISPLAY 0.617021 (-75 2910);
PAINT PINK (-75 2910);
FORCEPROP 2 LAST CDS_LIB mstr_standard
J 2
(-75 2900);
DISPLAY 0.787234 (-75 2900);
PAINT MONO (-75 2900);
DISPLAY INVISIBLE (-75 2900);
FORCEPROP 1 LAST BODY_TYPE PLUMBING
J 2
(-75 2850);
DISPLAY 1.234043 (-75 2850);
PAINT GREEN (-75 2850);
DISPLAY INVISIBLE (-75 2850);
FORCEPROP 1 LAST HDL_TAP TRUE
J 2
(-400 2775);
DISPLAY 1.234043 (-400 2775);
PAINT GREEN (-400 2775);
DISPLAY INVISIBLE (-400 2775);
FORCEPROP 1 LAST PATH I92
J 2
(-73 2900);
DISPLAY 0.872340 (-73 2900);
PAINT GREEN (-73 2900);
DISPLAY INVISIBLE (-73 2900);
FORCEADD TAP..6
R 2
(-75 2950);
FORCEPROP 3 LASTPIN (-125 2950) SIG_NAME M_B_DQ<37>
J 0
(-115 2960);
DISPLAY 0.659574 (-115 2960);
PAINT MONO (-115 2960);
DISPLAY INVISIBLE (-115 2960);
FORCEPROP 1 LASTPIN (-125 2950) BN 37
J 2
(-75 2960);
DISPLAY 0.617021 (-75 2960);
PAINT PINK (-75 2960);
FORCEPROP 2 LAST CDS_LIB mstr_standard
J 2
(-75 2950);
DISPLAY 0.787234 (-75 2950);
PAINT MONO (-75 2950);
DISPLAY INVISIBLE (-75 2950);
FORCEPROP 1 LAST BODY_TYPE PLUMBING
J 2
(-75 2900);
DISPLAY 1.234043 (-75 2900);
PAINT GREEN (-75 2900);
DISPLAY INVISIBLE (-75 2900);
FORCEPROP 1 LAST HDL_TAP TRUE
J 2
(-400 2825);
DISPLAY 1.234043 (-400 2825);
PAINT GREEN (-400 2825);
DISPLAY INVISIBLE (-400 2825);
FORCEPROP 1 LAST PATH I93
J 2
(-73 2950);
DISPLAY 0.872340 (-73 2950);
PAINT GREEN (-73 2950);
DISPLAY INVISIBLE (-73 2950);
FORCEADD TAP..6
R 2
(-75 3100);
FORCEPROP 3 LASTPIN (-125 3100) SIG_NAME M_B_DQ<40>
J 0
(-115 3110);
DISPLAY 0.659574 (-115 3110);
PAINT MONO (-115 3110);
DISPLAY INVISIBLE (-115 3110);
FORCEPROP 1 LASTPIN (-125 3100) BN 40
J 2
(-75 3110);
DISPLAY 0.617021 (-75 3110);
PAINT PINK (-75 3110);
FORCEPROP 2 LAST CDS_LIB mstr_standard
J 2
(-75 3100);
DISPLAY 0.787234 (-75 3100);
PAINT MONO (-75 3100);
DISPLAY INVISIBLE (-75 3100);
FORCEPROP 1 LAST BODY_TYPE PLUMBING
J 2
(-75 3050);
DISPLAY 1.234043 (-75 3050);
PAINT GREEN (-75 3050);
DISPLAY INVISIBLE (-75 3050);
FORCEPROP 1 LAST HDL_TAP TRUE
J 2
(-400 2975);
DISPLAY 1.234043 (-400 2975);
PAINT GREEN (-400 2975);
DISPLAY INVISIBLE (-400 2975);
FORCEPROP 1 LAST PATH I94
J 2
(-73 3100);
DISPLAY 0.872340 (-73 3100);
PAINT GREEN (-73 3100);
DISPLAY INVISIBLE (-73 3100);
FORCEADD TAP..6
R 2
(-75 3000);
FORCEPROP 3 LASTPIN (-125 3000) SIG_NAME M_B_DQ<38>
J 0
(-115 3010);
DISPLAY 0.659574 (-115 3010);
PAINT MONO (-115 3010);
DISPLAY INVISIBLE (-115 3010);
FORCEPROP 1 LASTPIN (-125 3000) BN 38
J 2
(-75 3010);
DISPLAY 0.617021 (-75 3010);
PAINT PINK (-75 3010);
FORCEPROP 2 LAST CDS_LIB mstr_standard
J 2
(-75 3000);
DISPLAY 0.787234 (-75 3000);
PAINT MONO (-75 3000);
DISPLAY INVISIBLE (-75 3000);
FORCEPROP 1 LAST BODY_TYPE PLUMBING
J 2
(-75 2950);
DISPLAY 1.234043 (-75 2950);
PAINT GREEN (-75 2950);
DISPLAY INVISIBLE (-75 2950);
FORCEPROP 1 LAST HDL_TAP TRUE
J 2
(-400 2875);
DISPLAY 1.234043 (-400 2875);
PAINT GREEN (-400 2875);
DISPLAY INVISIBLE (-400 2875);
FORCEPROP 1 LAST PATH I95
J 2
(-73 3000);
DISPLAY 0.872340 (-73 3000);
PAINT GREEN (-73 3000);
DISPLAY INVISIBLE (-73 3000);
FORCEADD TAP..6
R 2
(-75 3050);
FORCEPROP 3 LASTPIN (-125 3050) SIG_NAME M_B_DQ<39>
J 0
(-115 3060);
DISPLAY 0.659574 (-115 3060);
PAINT MONO (-115 3060);
DISPLAY INVISIBLE (-115 3060);
FORCEPROP 1 LASTPIN (-125 3050) BN 39
J 2
(-75 3060);
DISPLAY 0.617021 (-75 3060);
PAINT PINK (-75 3060);
FORCEPROP 2 LAST CDS_LIB mstr_standard
J 2
(-75 3050);
DISPLAY 0.787234 (-75 3050);
PAINT MONO (-75 3050);
DISPLAY INVISIBLE (-75 3050);
FORCEPROP 1 LAST BODY_TYPE PLUMBING
J 2
(-75 3000);
DISPLAY 1.234043 (-75 3000);
PAINT GREEN (-75 3000);
DISPLAY INVISIBLE (-75 3000);
FORCEPROP 1 LAST HDL_TAP TRUE
J 2
(-400 2925);
DISPLAY 1.234043 (-400 2925);
PAINT GREEN (-400 2925);
DISPLAY INVISIBLE (-400 2925);
FORCEPROP 1 LAST PATH I96
J 2
(-73 3050);
DISPLAY 0.872340 (-73 3050);
PAINT GREEN (-73 3050);
DISPLAY INVISIBLE (-73 3050);
FORCEADD TAP..6
R 2
(-75 3200);
FORCEPROP 3 LASTPIN (-125 3200) SIG_NAME M_B_DQ<42>
J 0
(-115 3210);
DISPLAY 0.659574 (-115 3210);
PAINT MONO (-115 3210);
DISPLAY INVISIBLE (-115 3210);
FORCEPROP 1 LASTPIN (-125 3200) BN 42
J 2
(-75 3210);
DISPLAY 0.617021 (-75 3210);
PAINT PINK (-75 3210);
FORCEPROP 2 LAST CDS_LIB mstr_standard
J 2
(-75 3200);
DISPLAY 0.787234 (-75 3200);
PAINT MONO (-75 3200);
DISPLAY INVISIBLE (-75 3200);
FORCEPROP 1 LAST BODY_TYPE PLUMBING
J 2
(-75 3150);
DISPLAY 1.234043 (-75 3150);
PAINT GREEN (-75 3150);
DISPLAY INVISIBLE (-75 3150);
FORCEPROP 1 LAST HDL_TAP TRUE
J 2
(-400 3075);
DISPLAY 1.234043 (-400 3075);
PAINT GREEN (-400 3075);
DISPLAY INVISIBLE (-400 3075);
FORCEPROP 1 LAST PATH I97
J 2
(-73 3200);
DISPLAY 0.872340 (-73 3200);
PAINT GREEN (-73 3200);
DISPLAY INVISIBLE (-73 3200);
FORCEADD TAP..6
R 2
(-75 3150);
FORCEPROP 3 LASTPIN (-125 3150) SIG_NAME M_B_DQ<41>
J 0
(-115 3160);
DISPLAY 0.659574 (-115 3160);
PAINT MONO (-115 3160);
DISPLAY INVISIBLE (-115 3160);
FORCEPROP 1 LASTPIN (-125 3150) BN 41
J 2
(-75 3160);
DISPLAY 0.617021 (-75 3160);
PAINT PINK (-75 3160);
FORCEPROP 2 LAST CDS_LIB mstr_standard
J 2
(-75 3150);
DISPLAY 0.787234 (-75 3150);
PAINT MONO (-75 3150);
DISPLAY INVISIBLE (-75 3150);
FORCEPROP 1 LAST BODY_TYPE PLUMBING
J 2
(-75 3100);
DISPLAY 1.234043 (-75 3100);
PAINT GREEN (-75 3100);
DISPLAY INVISIBLE (-75 3100);
FORCEPROP 1 LAST HDL_TAP TRUE
J 2
(-400 3025);
DISPLAY 1.234043 (-400 3025);
PAINT GREEN (-400 3025);
DISPLAY INVISIBLE (-400 3025);
FORCEPROP 1 LAST PATH I98
J 2
(-73 3150);
DISPLAY 0.872340 (-73 3150);
PAINT GREEN (-73 3150);
DISPLAY INVISIBLE (-73 3150);
FORCEADD TAP..6
R 2
(-75 3300);
FORCEPROP 3 LASTPIN (-125 3300) SIG_NAME M_B_DQ<44>
J 0
(-115 3310);
DISPLAY 0.659574 (-115 3310);
PAINT MONO (-115 3310);
DISPLAY INVISIBLE (-115 3310);
FORCEPROP 1 LASTPIN (-125 3300) BN 44
J 2
(-75 3310);
DISPLAY 0.617021 (-75 3310);
PAINT PINK (-75 3310);
FORCEPROP 2 LAST CDS_LIB mstr_standard
J 2
(-75 3300);
DISPLAY 0.787234 (-75 3300);
PAINT MONO (-75 3300);
DISPLAY INVISIBLE (-75 3300);
FORCEPROP 1 LAST BODY_TYPE PLUMBING
J 2
(-75 3250);
DISPLAY 1.234043 (-75 3250);
PAINT GREEN (-75 3250);
DISPLAY INVISIBLE (-75 3250);
FORCEPROP 1 LAST HDL_TAP TRUE
J 2
(-400 3175);
DISPLAY 1.234043 (-400 3175);
PAINT GREEN (-400 3175);
DISPLAY INVISIBLE (-400 3175);
FORCEPROP 1 LAST PATH I99
J 2
(-73 3300);
DISPLAY 0.872340 (-73 3300);
PAINT GREEN (-73 3300);
DISPLAY INVISIBLE (-73 3300);
FORCEADD BOM_NOTE..1
(-3450 5000);
FORCEPROP 0 LAST L1 UNSTUFF FOR SKU B
J 0
(-3600 4900);
DISPLAY 1.063830 (-3600 4900);
PAINT WHITE (-3600 4900);
FORCEPROP 2 LAST BOM_COST SB
J 0
(-3600 4975);
DISPLAY 1.361702 (-3600 4975);
PAINT ORANGE (-3600 4975);
DISPLAY INVISIBLE (-3600 4975);
FORCEPROP 2 LAST CDS_LIB mstr_symbols
J 0
(-3450 5000);
PAINT ORANGE (-3450 5000);
DISPLAY INVISIBLE (-3450 5000);
FORCEPROP 1 LAST COMMENT_BODY TRUE
J 0
(-3425 5100);
DISPLAY 1.319149 (-3425 5100);
PAINT ORANGE (-3425 5100);
DISPLAY INVISIBLE (-3425 5100);
FORCEPROP 2 LAST ROOM SB_HEADERS
J 0
(-3600 4975);
DISPLAY 1.361702 (-3600 4975);
PAINT ORANGE (-3600 4975);
DISPLAY INVISIBLE (-3600 4975);
FORCEADD INTEL_CORP_BPAGE..1
(4250 200);
FORCEPROP 1 LAST CDS_CON_LAST_MODIFIED Tue Dec 01 11:51:27 2015
J 0
(2825 525);
PAINT ORANGE (2825 525);
DISPLAY INVISIBLE (2825 525);
FORCEPROP 1 LAST CUSTOM_TXT_CDS <CURRENT_DESIGN_SHEET> OF <TOTAL_DESIGN_SHEETS>
J 0
(3750 225);
PAINT GREEN (3750 225);
FORCEPROP 1 LAST CUSTOM_TXT_CDS <CON_LAST_MODIFIED>
J 0
(2325 550);
PAINT GREEN (2325 550);
FORCEPROP 2 LAST CUSTOM_TXT_CDS <XR_PAGE_TITLE>
J 0
(-3640 5450);
DISPLAY 0.638298 (-3640 5450);
PAINT PINK (-3640 5450);
DISPLAY INVISIBLE (-3640 5450);
FORCEPROP 1 LAST SCH_ADDRESS3 Santa Clara, CA 95052-8119
J 0
(275 225);
DISPLAY 0.617021 (275 225);
PAINT GREEN (275 225);
FORCEPROP 1 LAST SCH_ADDRESS2 P.O. BOX 58119
J 0
(275 275);
DISPLAY 0.617021 (275 275);
PAINT GREEN (275 275);
FORCEPROP 1 LAST SCH_ADDRESS1 2200 Mission College Blvd.
J 0
(275 325);
DISPLAY 0.617021 (275 325);
PAINT GREEN (275 325);
FORCEPROP 1 LAST SCH_TITLE CPU0 DDR4 CH B DIMM1
J 0
(-3700 250);
DISPLAY 1.212766 (-3700 250);
PAINT ORANGE (-3700 250);
FORCEPROP 1 LAST SCH_NUMBER H4694802
J 0
(2950 350);
DISPLAY 1.212766 (2950 350);
PAINT YELLOW (2950 350);
FORCEPROP 1 LAST SCH_DEPT BESD
J 1
(-200 300);
DISPLAY 1.212766 (-200 300);
PAINT YELLOW (-200 300);
FORCEPROP 1 LAST SCH_REV 2.420
J 0
(4000 350);
DISPLAY 0.978723 (4000 350);
PAINT YELLOW (4000 350);
FORCEPROP 2 LAST CDS_LIB mstr_symbols
J 0
(4250 200);
PAINT MONO (4250 200);
DISPLAY INVISIBLE (4250 200);
FORCEPROP 2 LAST PAGE_BORDER TRUE
J 0
(-3640 5450);
DISPLAY 0.638298 (-3640 5450);
PAINT PINK (-3640 5450);
DISPLAY INVISIBLE (-3640 5450);
FORCEPROP 1 LAST COMMENT_BODY TRUE
J 0
(4262 212);
DISPLAY 0.468085 (4262 212);
PAINT GREEN (4262 212);
DISPLAY INVISIBLE (4262 212);
FORCEPROP 2 LAST CDS_XR_PAGE_TITLE CR-46 : @BASEBOARD_FAB2_LIB.BASEBOARD_FAB2(SCH_1):PAGE46
J 0
(-3640 5450);
DISPLAY 0.638298 (-3640 5450);
PAINT PINK (-3640 5450);
DISPLAY INVISIBLE (-3640 5450);
WIRE 17 -1 (2575 4575)(2575 4675);
WIRE 17 -1 (2575 4475)(2575 4575);
WIRE 17 -1 (2575 4675)(2575 4775);
WIRE 17 -1 (2575 4775)(2575 4800);
WIRE 17 -1 (2575 4375)(2575 4475);
WIRE 17 -1 (2575 4275)(2575 4375);
WIRE 17 -1 (3175 4800)(2575 4800);
FORCEPROP 2 LAST SIG_NAME M_B_DQS_DN<17:0>
J 0
(2625 4810);
DISPLAY 0.617021 (2625 4810);
PAINT ORANGE (2625 4810);
WIRE 17 -1 (2375 4625)(2375 4725);
WIRE 17 -1 (2375 4525)(2375 4625);
WIRE 17 -1 (2375 4725)(2375 4825);
WIRE 17 -1 (2375 4825)(2375 4850);
WIRE 17 -1 (2375 4425)(2375 4525);
WIRE 17 -1 (2375 4325)(2375 4425);
WIRE 17 -1 (3175 4850)(2375 4850);
FORCEPROP 2 LAST SIG_NAME M_B_DQS_DP<17:0>
J 0
(2625 4860);
DISPLAY 0.617021 (2625 4860);
PAINT ORANGE (2625 4860);
WIRE 17 -1 (2575 4175)(2575 4275);
WIRE 17 -1 (2575 4075)(2575 4175);
WIRE 17 -1 (2575 3975)(2575 4075);
WIRE 17 -1 (2575 3875)(2575 3975);
WIRE 17 -1 (2575 3775)(2575 3875);
WIRE 17 -1 (2575 3675)(2575 3775);
WIRE 17 -1 (2575 3575)(2575 3675);
WIRE 17 -1 (2575 3475)(2575 3575);
WIRE 17 -1 (2375 4225)(2375 4325);
WIRE 17 -1 (2375 4125)(2375 4225);
WIRE 17 -1 (2375 4025)(2375 4125);
WIRE 17 -1 (2375 3925)(2375 4025);
WIRE 17 -1 (2375 3825)(2375 3925);
WIRE 17 -1 (2375 3725)(2375 3825);
WIRE 17 -1 (2375 3625)(2375 3725);
WIRE 17 -1 (2375 3525)(2375 3625);
WIRE 17 -1 (2375 3425)(2375 3525);
WIRE 17 -1 (2575 3375)(2575 3475);
WIRE 17 -1 (2575 3275)(2575 3375);
WIRE 17 -1 (2575 3175)(2575 3275);
WIRE 17 -1 (2575 3075)(2575 3175);
WIRE 17 -1 (2375 3325)(2375 3425);
WIRE 17 -1 (2375 3225)(2375 3325);
WIRE 17 -1 (2375 3125)(2375 3225);
WIRE 17 -1 (-25 4225)(-25 4275);
WIRE 17 -1 (-25 4175)(-25 4225);
WIRE 17 -1 (-25 4275)(-25 4300);
WIRE 17 -1 (425 4300)(-25 4300);
FORCEPROP 2 LAST SIG_NAME M_B_DQ<63:0>
J 0
(15 4310);
DISPLAY 0.617021 (15 4310);
PAINT ORANGE (15 4310);
WIRE 17 -1 (-25 4125)(-25 4175);
WIRE 17 -1 (-25 4075)(-25 4125);
WIRE 17 -1 (-25 4025)(-25 4075);
WIRE 17 -1 (-25 3975)(-25 4025);
WIRE 17 -1 (-1625 4275)(-1625 4300);
WIRE 17 -1 (-1625 4225)(-1625 4275);
WIRE 17 -1 (-2175 4300)(-1625 4300);
FORCEPROP 2 LAST SIG_NAME M_B_MA<17:0>
J 0
(-2125 4310);
DISPLAY 0.617021 (-2125 4310);
PAINT ORANGE (-2125 4310);
WIRE 17 -1 (-1625 4125)(-1625 4175);
WIRE 17 -1 (-1625 4075)(-1625 4125);
WIRE 17 -1 (-1625 4175)(-1625 4225);
WIRE 17 -1 (-1625 4025)(-1625 4075);
WIRE 17 -1 (-1625 3975)(-1625 4025);
WIRE 17 -1 (-25 3925)(-25 3975);
WIRE 17 -1 (-25 3875)(-25 3925);
WIRE 17 -1 (-25 3825)(-25 3875);
WIRE 17 -1 (-25 3775)(-25 3825);
WIRE 17 -1 (-25 3725)(-25 3775);
WIRE 17 -1 (-25 3675)(-25 3725);
WIRE 17 -1 (-25 3625)(-25 3675);
WIRE 17 -1 (-25 3575)(-25 3625);
WIRE 17 -1 (-25 3525)(-25 3575);
WIRE 17 -1 (-25 3475)(-25 3525);
WIRE 17 -1 (-25 3425)(-25 3475);
WIRE 17 -1 (-25 3375)(-25 3425);
WIRE 17 -1 (-25 3325)(-25 3375);
WIRE 17 -1 (-25 3275)(-25 3325);
WIRE 17 -1 (-25 3225)(-25 3275);
WIRE 17 -1 (-25 3175)(-25 3225);
WIRE 17 -1 (-25 3125)(-25 3175);
WIRE 17 -1 (-25 3075)(-25 3125);
WIRE 17 -1 (-25 3025)(-25 3075);
WIRE 17 -1 (-25 2975)(-25 3025);
WIRE 17 -1 (-25 2925)(-25 2975);
WIRE 17 -1 (-25 2875)(-25 2925);
WIRE 17 -1 (-25 2825)(-25 2875);
WIRE 17 -1 (-25 2775)(-25 2825);
WIRE 17 -1 (-25 2725)(-25 2775);
WIRE 17 -1 (-25 2675)(-25 2725);
WIRE 17 -1 (-25 2625)(-25 2675);
WIRE 17 -1 (-25 2575)(-25 2625);
WIRE 17 -1 (-25 2525)(-25 2575);
WIRE 17 -1 (-25 2475)(-25 2525);
WIRE 17 -1 (-25 2425)(-25 2475);
WIRE 17 -1 (-25 2375)(-25 2425);
WIRE 17 -1 (-25 2325)(-25 2375);
WIRE 17 -1 (-25 2275)(-25 2325);
WIRE 17 -1 (-25 2225)(-25 2275);
WIRE 17 -1 (-25 2175)(-25 2225);
WIRE 17 -1 (-25 2125)(-25 2175);
WIRE 17 -1 (-25 2075)(-25 2125);
WIRE 17 -1 (-25 2025)(-25 2075);
WIRE 17 -1 (-25 1975)(-25 2025);
WIRE 17 -1 (-25 1925)(-25 1975);
WIRE 17 -1 (-25 1875)(-25 1925);
WIRE 17 -1 (-25 1825)(-25 1875);
WIRE 17 -1 (-25 1775)(-25 1825);
WIRE 17 -1 (-25 1725)(-25 1775);
WIRE 17 -1 (-25 1675)(-25 1725);
WIRE 17 -1 (-25 1625)(-25 1675);
WIRE 17 -1 (-25 1575)(-25 1625);
WIRE 17 -1 (-25 1525)(-25 1575);
WIRE 17 -1 (-25 1475)(-25 1525);
WIRE 17 -1 (-25 1425)(-25 1475);
WIRE 17 -1 (-25 1375)(-25 1425);
WIRE 17 -1 (-25 1325)(-25 1375);
WIRE 17 -1 (-25 1275)(-25 1325);
WIRE 17 -1 (-25 1225)(-25 1275);
WIRE 17 -1 (-25 1175)(-25 1225);
WIRE 17 -1 (-25 1125)(-25 1175);
WIRE 17 -1 (-1625 3925)(-1625 3975);
WIRE 17 -1 (-1625 3875)(-1625 3925);
WIRE 17 -1 (-1625 3825)(-1625 3875);
WIRE 17 -1 (-1625 3775)(-1625 3825);
WIRE 17 -1 (-1625 3725)(-1625 3775);
WIRE 17 -1 (-1625 3675)(-1625 3725);
WIRE 17 -1 (-1625 3625)(-1625 3675);
WIRE 17 -1 (-1625 3575)(-1625 3625);
WIRE 17 -1 (-1625 3525)(-1625 3575);
WIRE 17 -1 (-1625 3475)(-1625 3525);
WIRE 17 -1 (-1625 3425)(-1625 3475);
WIRE 17 -1 (-1625 3275)(-1625 3325);
WIRE 17 -1 (-1625 3350)(-1625 3325);
WIRE 17 -1 (-1625 3350)(-2175 3350);
FORCEPROP 2 LAST SIG_NAME M_B_BA<1:0>
J 0
(-2125 3360);
DISPLAY 0.617021 (-2125 3360);
PAINT ORANGE (-2125 3360);
WIRE 17 -1 (-1625 3175)(-1625 3225);
WIRE 17 -1 (-1625 3225)(-1625 3250);
WIRE 17 -1 (-1625 3250)(-2175 3250);
FORCEPROP 2 LAST SIG_NAME M_B_BG<1:0>
J 0
(-2125 3260);
DISPLAY 0.617021 (-2125 3260);
PAINT ORANGE (-2125 3260);
WIRE 17 -1 (-1625 2975)(-1625 3075);
WIRE 17 -1 (-1625 3075)(-1625 3150);
WIRE 17 -1 (-1625 3150)(-2325 3150);
FORCEPROP 2 LAST SIG_NAME M_B_CLK_DP<3:0>
J 0
(-2275 3160);
DISPLAY 0.617021 (-2275 3160);
PAINT ORANGE (-2275 3160);
WIRE 17 -1 (-1625 2725)(-1625 2775);
WIRE 17 -1 (-1625 2675)(-1625 2725);
WIRE 17 -1 (-1625 2775)(-1625 2800);
WIRE 17 -1 (-1625 2800)(-2175 2800);
FORCEPROP 2 LAST SIG_NAME M_B_CS_N<7:0>
J 0
(-2125 2810);
DISPLAY 0.617021 (-2125 2810);
PAINT ORANGE (-2125 2810);
WIRE 17 -1 (-1625 2625)(-1625 2675);
WIRE 17 -1 (-1625 2525)(-1625 2600);
WIRE 17 -1 (-1625 2475)(-1625 2525);
WIRE 17 -1 (-1625 2600)(-2175 2600);
FORCEPROP 2 LAST SIG_NAME M_B_CKE<3:0>
J 0
(-2150 2610);
DISPLAY 0.617021 (-2150 2610);
PAINT ORANGE (-2150 2610);
WIRE 17 -1 (-1625 2375)(-1625 2450);
WIRE 17 -1 (-1625 2325)(-1625 2375);
WIRE 17 -1 (-1625 2450)(-2175 2450);
FORCEPROP 2 LAST SIG_NAME M_B_ODT<3:0>
J 0
(-2150 2460);
DISPLAY 0.617021 (-2150 2460);
PAINT ORANGE (-2150 2460);
WIRE 17 -1 (-1625 2125)(-1625 2175);
WIRE 17 -1 (-1625 2075)(-1625 2125);
WIRE 17 -1 (-1625 2175)(-1625 2225);
WIRE 17 -1 (-1625 2225)(-1625 2250);
WIRE 17 -1 (-1625 2025)(-1625 2075);
WIRE 17 -1 (-1625 1975)(-1625 2025);
WIRE 17 -1 (-1625 2250)(-2175 2250);
FORCEPROP 2 LAST SIG_NAME M_B_ECC<7:0>
J 0
(-2150 2260);
DISPLAY 0.617021 (-2150 2260);
PAINT ORANGE (-2150 2260);
WIRE 17 -1 (-1625 1925)(-1625 1975);
WIRE 17 -1 (-1825 3025)(-1825 3100);
WIRE 17 -1 (-1825 3025)(-1825 2925);
WIRE 17 -1 (-1825 3100)(-2325 3100);
FORCEPROP 2 LAST SIG_NAME M_B_CLK_DN<3:0>
J 0
(-2275 3110);
DISPLAY 0.617021 (-2275 3110);
PAINT ORANGE (-2275 3110);
WIRE 17 -1 (-1625 1875)(-1625 1925);
WIRE 16 -1 (-2975 800)(-2975 700);
WIRE 16 -1 (975 800)(1175 800);
WIRE 16 -1 (975 800)(975 850);
WIRE 16 -1 (975 850)(1175 850);
WIRE 16 -1 (975 850)(975 900);
WIRE 16 -1 (975 900)(1175 900);
WIRE 16 -1 (975 900)(975 950);
WIRE 16 -1 (975 950)(1175 950);
WIRE 16 -1 (975 950)(975 1000);
WIRE 16 -1 (975 1000)(1175 1000);
WIRE 16 -1 (975 1000)(975 1050);
WIRE 16 -1 (975 1050)(1175 1050);
WIRE 16 -1 (975 1050)(975 1100);
WIRE 16 -1 (975 1100)(1175 1100);
WIRE 16 -1 (975 1100)(975 1150);
WIRE 16 -1 (975 1150)(1175 1150);
WIRE 16 -1 (975 1150)(975 1200);
WIRE 16 -1 (975 1200)(1175 1200);
WIRE 16 -1 (975 1200)(975 1250);
WIRE 16 -1 (975 1250)(1175 1250);
WIRE 16 -1 (975 1250)(975 1300);
WIRE 16 -1 (975 1300)(1175 1300);
WIRE 16 -1 (975 1300)(975 1350);
WIRE 16 -1 (975 1350)(1175 1350);
WIRE 16 -1 (975 1350)(975 1400);
WIRE 16 -1 (975 1400)(1175 1400);
WIRE 16 -1 (975 1400)(975 1450);
WIRE 16 -1 (975 1450)(1175 1450);
WIRE 16 -1 (975 1450)(975 1500);
WIRE 16 -1 (975 1500)(1175 1500);
WIRE 16 -1 (975 1500)(975 1550);
WIRE 16 -1 (975 1550)(1175 1550);
WIRE 16 -1 (975 1550)(975 1600);
WIRE 16 -1 (975 1600)(1175 1600);
WIRE 16 -1 (975 1600)(975 1650);
WIRE 16 -1 (975 1650)(1175 1650);
WIRE 16 -1 (975 1650)(975 1700);
WIRE 16 -1 (975 1700)(1175 1700);
WIRE 16 -1 (975 1700)(975 1750);
WIRE 16 -1 (975 1750)(1175 1750);
WIRE 16 -1 (975 1750)(975 1800);
WIRE 16 -1 (975 1800)(1175 1800);
WIRE 16 -1 (975 1800)(975 1850);
WIRE 16 -1 (975 1850)(1175 1850);
WIRE 16 -1 (975 1850)(975 1900);
WIRE 16 -1 (975 1900)(1175 1900);
WIRE 16 -1 (975 1900)(975 1950);
WIRE 16 -1 (975 1950)(1175 1950);
WIRE 16 -1 (975 1950)(975 2000);
WIRE 16 -1 (975 2000)(975 2050);
WIRE 16 -1 (975 2000)(1175 2000);
WIRE 16 -1 (975 2050)(1175 2050);
WIRE 16 -1 (600 2050)(975 2050);
WIRE 16 -1 (600 2150)(600 2050);
WIRE 16 -1 (975 2150)(1175 2150);
WIRE 16 -1 (975 2150)(975 2200);
WIRE 16 -1 (975 2200)(1175 2200);
WIRE 16 -1 (825 2200)(975 2200);
WIRE 16 -1 (825 2300)(825 2200);
WIRE 16 -1 (975 2300)(1175 2300);
WIRE 16 -1 (975 2350)(975 2300);
WIRE 16 -1 (975 2350)(1175 2350);
WIRE 16 -1 (975 2400)(975 2350);
WIRE 16 -1 (975 2400)(1175 2400);
WIRE 16 -1 (975 2400)(975 2450);
WIRE 16 -1 (975 2450)(1175 2450);
WIRE 16 -1 (975 2500)(975 2450);
WIRE 16 -1 (975 2500)(1175 2500);
WIRE 16 -1 (975 2600)(975 2500);
WIRE 16 -1 (2725 3400)(2925 3400);
WIRE 16 -1 (2725 3350)(2725 3400);
WIRE 16 -1 (2725 3350)(2925 3350);
WIRE 16 -1 (2725 3300)(2725 3350);
WIRE 16 -1 (2725 3300)(2925 3300);
WIRE 16 -1 (2725 3250)(2725 3300);
WIRE 16 -1 (2725 3250)(2925 3250);
WIRE 16 -1 (2725 3200)(2725 3250);
WIRE 16 -1 (2725 3200)(2925 3200);
WIRE 16 -1 (2725 3150)(2725 3200);
WIRE 16 -1 (2725 3150)(2925 3150);
WIRE 16 -1 (2725 3100)(2725 3150);
WIRE 16 -1 (2725 3100)(2925 3100);
WIRE 16 -1 (2725 3050)(2725 3100);
WIRE 16 -1 (2725 3050)(2925 3050);
WIRE 16 -1 (2725 3000)(2725 3050);
WIRE 16 -1 (2725 3000)(2925 3000);
WIRE 16 -1 (2725 2950)(2725 3000);
WIRE 16 -1 (2725 2950)(2925 2950);
WIRE 16 -1 (2725 2900)(2725 2950);
WIRE 16 -1 (2725 2900)(2925 2900);
WIRE 16 -1 (2725 2850)(2725 2900);
WIRE 16 -1 (2725 2850)(2925 2850);
WIRE 16 -1 (2725 2800)(2725 2850);
WIRE 16 -1 (2725 2800)(2925 2800);
WIRE 16 -1 (2725 2750)(2725 2800);
WIRE 16 -1 (2725 2750)(2925 2750);
WIRE 16 -1 (2725 2700)(2725 2750);
WIRE 16 -1 (2725 2700)(2925 2700);
WIRE 16 -1 (2725 2650)(2725 2700);
WIRE 16 -1 (2725 2650)(2925 2650);
WIRE 16 -1 (2725 2600)(2725 2650);
WIRE 16 -1 (2725 2600)(2925 2600);
WIRE 16 -1 (2725 2550)(2725 2600);
WIRE 16 -1 (2725 2550)(2925 2550);
WIRE 16 -1 (2725 2500)(2725 2550);
WIRE 16 -1 (2725 2500)(2925 2500);
WIRE 16 -1 (2725 2450)(2725 2500);
WIRE 16 -1 (2725 2450)(2925 2450);
WIRE 16 -1 (2725 2400)(2725 2450);
WIRE 16 -1 (2725 2400)(2925 2400);
WIRE 16 -1 (2725 2350)(2725 2400);
WIRE 16 -1 (2725 2350)(2925 2350);
WIRE 16 -1 (2725 2300)(2725 2350);
WIRE 16 -1 (2725 2300)(2925 2300);
WIRE 16 -1 (2725 2250)(2725 2300);
WIRE 16 -1 (2725 2250)(2925 2250);
WIRE 16 -1 (2725 2200)(2725 2250);
WIRE 16 -1 (2725 2200)(2925 2200);
WIRE 16 -1 (2725 2150)(2725 2200);
WIRE 16 -1 (2725 2150)(2925 2150);
WIRE 16 -1 (2725 2100)(2725 2150);
WIRE 16 -1 (2725 2100)(2925 2100);
WIRE 16 -1 (2725 2050)(2725 2100);
WIRE 16 -1 (2725 2050)(2925 2050);
WIRE 16 -1 (2725 2000)(2725 2050);
WIRE 16 -1 (2725 2000)(2925 2000);
WIRE 16 -1 (2725 1950)(2725 2000);
WIRE 16 -1 (2725 1950)(2925 1950);
WIRE 16 -1 (2725 1900)(2725 1950);
WIRE 16 -1 (2725 1900)(2925 1900);
WIRE 16 -1 (2725 1850)(2725 1900);
WIRE 16 -1 (2725 1850)(2925 1850);
WIRE 16 -1 (2725 1800)(2725 1850);
WIRE 16 -1 (2725 1800)(2925 1800);
WIRE 16 -1 (2725 1750)(2725 1800);
WIRE 16 -1 (2725 1750)(2925 1750);
WIRE 16 -1 (2725 1700)(2725 1750);
WIRE 16 -1 (2725 1700)(2925 1700);
WIRE 16 -1 (2725 1650)(2725 1700);
WIRE 16 -1 (2725 1650)(2925 1650);
WIRE 16 -1 (2725 1600)(2725 1650);
WIRE 16 -1 (2725 1600)(2925 1600);
WIRE 16 -1 (2725 1550)(2725 1600);
WIRE 16 -1 (2725 1550)(2925 1550);
WIRE 16 -1 (2725 1500)(2725 1550);
WIRE 16 -1 (2725 1500)(2925 1500);
WIRE 16 -1 (2725 1450)(2725 1500);
WIRE 16 -1 (2725 1450)(2925 1450);
WIRE 16 -1 (2725 1400)(2725 1450);
WIRE 16 -1 (2725 1400)(2925 1400);
WIRE 16 -1 (2725 1350)(2725 1400);
WIRE 16 -1 (2725 1350)(2925 1350);
WIRE 16 -1 (2725 1300)(2725 1350);
WIRE 16 -1 (2725 1300)(2925 1300);
WIRE 16 -1 (2725 1250)(2725 1300);
WIRE 16 -1 (2725 1250)(2925 1250);
WIRE 16 -1 (2725 1200)(2725 1250);
WIRE 16 -1 (2725 1200)(2925 1200);
WIRE 16 -1 (2725 1150)(2725 1200);
WIRE 16 -1 (2725 1150)(2925 1150);
WIRE 16 -1 (2725 1100)(2725 1150);
WIRE 16 -1 (2725 1100)(2925 1100);
WIRE 16 -1 (2725 1000)(2725 1100);
WIRE 16 -1 (4125 3350)(4125 3400);
WIRE 16 -1 (4125 3300)(4125 3350);
WIRE 16 -1 (4125 3350)(3925 3350);
WIRE 16 -1 (4125 3400)(3925 3400);
WIRE 16 -1 (4125 3250)(4125 3300);
WIRE 16 -1 (4125 3300)(3925 3300);
WIRE 16 -1 (4125 3200)(4125 3250);
WIRE 16 -1 (4125 3250)(3925 3250);
WIRE 16 -1 (4125 3150)(4125 3200);
WIRE 16 -1 (4125 3200)(3925 3200);
WIRE 16 -1 (4125 3100)(4125 3150);
WIRE 16 -1 (4125 3150)(3925 3150);
WIRE 16 -1 (4125 3050)(4125 3100);
WIRE 16 -1 (4125 3100)(3925 3100);
WIRE 16 -1 (4125 3000)(4125 3050);
WIRE 16 -1 (4125 3050)(3925 3050);
WIRE 16 -1 (4125 2950)(4125 3000);
WIRE 16 -1 (4125 3000)(3925 3000);
WIRE 16 -1 (4125 2900)(4125 2950);
WIRE 16 -1 (4125 2950)(3925 2950);
WIRE 16 -1 (4125 2850)(4125 2900);
WIRE 16 -1 (4125 2900)(3925 2900);
WIRE 16 -1 (4125 2800)(4125 2850);
WIRE 16 -1 (4125 2850)(3925 2850);
WIRE 16 -1 (4125 2800)(4125 2750);
WIRE 16 -1 (4125 2800)(3925 2800);
WIRE 16 -1 (4125 2700)(4125 2750);
WIRE 16 -1 (4125 2750)(3925 2750);
WIRE 16 -1 (4125 2700)(4125 2650);
WIRE 16 -1 (4125 2700)(3925 2700);
WIRE 16 -1 (4125 2650)(4125 2600);
WIRE 16 -1 (4125 2650)(3925 2650);
WIRE 16 -1 (4125 2600)(4125 2550);
WIRE 16 -1 (4125 2600)(3925 2600);
WIRE 16 -1 (4125 2550)(4125 2500);
WIRE 16 -1 (4125 2550)(3925 2550);
WIRE 16 -1 (4125 2500)(4125 2450);
WIRE 16 -1 (4125 2500)(3925 2500);
WIRE 16 -1 (4125 2450)(4125 2400);
WIRE 16 -1 (4125 2450)(3925 2450);
WIRE 16 -1 (4125 2400)(4125 2350);
WIRE 16 -1 (4125 2400)(3925 2400);
WIRE 16 -1 (4125 2350)(4125 2300);
WIRE 16 -1 (4125 2350)(3925 2350);
WIRE 16 -1 (4125 2300)(4125 2250);
WIRE 16 -1 (4125 2300)(3925 2300);
WIRE 16 -1 (4125 2250)(4125 2200);
WIRE 16 -1 (4125 2250)(3925 2250);
WIRE 16 -1 (4125 2200)(4125 2150);
WIRE 16 -1 (4125 2200)(3925 2200);
WIRE 16 -1 (4125 2150)(4125 2100);
WIRE 16 -1 (4125 2150)(3925 2150);
WIRE 16 -1 (4125 2100)(4125 2050);
WIRE 16 -1 (4125 2100)(3925 2100);
WIRE 16 -1 (4125 2050)(4125 2000);
WIRE 16 -1 (4125 2050)(3925 2050);
WIRE 16 -1 (4125 2000)(4125 1950);
WIRE 16 -1 (4125 2000)(3925 2000);
WIRE 16 -1 (4125 1950)(4125 1900);
WIRE 16 -1 (4125 1950)(3925 1950);
WIRE 16 -1 (4125 1900)(4125 1850);
WIRE 16 -1 (4125 1900)(3925 1900);
WIRE 16 -1 (4125 1850)(4125 1800);
WIRE 16 -1 (4125 1850)(3925 1850);
WIRE 16 -1 (4125 1800)(4125 1750);
WIRE 16 -1 (4125 1800)(3925 1800);
WIRE 16 -1 (4125 1750)(4125 1700);
WIRE 16 -1 (4125 1750)(3925 1750);
WIRE 16 -1 (4125 1700)(4125 1650);
WIRE 16 -1 (4125 1700)(3925 1700);
WIRE 16 -1 (4125 1650)(4125 1600);
WIRE 16 -1 (4125 1650)(3925 1650);
WIRE 16 -1 (4125 1600)(4125 1550);
WIRE 16 -1 (4125 1600)(3925 1600);
WIRE 16 -1 (4125 1550)(4125 1500);
WIRE 16 -1 (4125 1550)(3925 1550);
WIRE 16 -1 (4125 1500)(4125 1450);
WIRE 16 -1 (4125 1500)(3925 1500);
WIRE 16 -1 (4125 1450)(4125 1400);
WIRE 16 -1 (4125 1450)(3925 1450);
WIRE 16 -1 (4125 1400)(4125 1350);
WIRE 16 -1 (4125 1400)(3925 1400);
WIRE 16 -1 (4125 1350)(4125 1300);
WIRE 16 -1 (4125 1350)(3925 1350);
WIRE 16 -1 (4125 1300)(4125 1250);
WIRE 16 -1 (4125 1300)(3925 1300);
WIRE 16 -1 (4125 1250)(4125 1200);
WIRE 16 -1 (4125 1250)(3925 1250);
WIRE 16 -1 (4125 1200)(4125 1150);
WIRE 16 -1 (4125 1200)(3925 1200);
WIRE 16 -1 (4125 1150)(4125 1100);
WIRE 16 -1 (4125 1150)(3925 1150);
WIRE 16 -1 (4125 1100)(4125 1000);
WIRE 16 -1 (4125 1100)(3925 1100);
WIRE 16 -1 (2175 2450)(2375 2450);
WIRE 16 -1 (2375 2450)(2375 2500);
WIRE 16 -1 (2175 2500)(2375 2500);
WIRE 16 -1 (2375 2500)(2375 2675);
WIRE 16 -1 (-3425 1400)(-1325 1400);
WIRE 16 -1 (-3425 1400)(-3425 1300);
WIRE 16 -1 (-1325 1300)(-1475 1300);
WIRE 16 -1 (-1475 1350)(-1475 1300);
WIRE 16 -1 (-1325 1350)(-1475 1350);
WIRE 16 -1 (-1475 1350)(-1475 1450);
WIRE 16 -1 (-1475 1450)(-1325 1450);
WIRE 16 -1 (-3425 1450)(-1475 1450);
WIRE 16 -1 (-3425 1550)(-3425 1450);
WIRE 16 -1 (-2975 1000)(-2975 1100);
WIRE 16 -1 (-1325 1100)(-2975 1100);
FORCEPROP 2 LAST SIG_NAME M_B_VREF
J 0
(-2125 1110);
DISPLAY 0.617021 (-2125 1110);
PAINT ORANGE (-2125 1110);
WIRE 16 -1 (-3075 1100)(-2975 1100);
WIRE 16 -1 (-2175 950)(-1325 950);
FORCEPROP 2 LAST SIG_NAME TP_CH_B_DIMM_B1_RFU_1
J 0
(-2125 960);
DISPLAY 0.617021 (-2125 960);
PAINT ORANGE (-2125 960);
FORCEPROP 2 LASTPROP $XRERR UNIQUE?
J 0
(-2415 950);
DISPLAY 0.638298 (-2415 950);
PAINT MONO (-2415 950);
DISPLAY INVISIBLE (-2415 950);
WIRE 16 -1 (-2175 900)(-1325 900);
FORCEPROP 2 LAST SIG_NAME TP_CH_B_DIMM_B1_RFU_0
J 0
(-2125 910);
DISPLAY 0.617021 (-2125 910);
PAINT ORANGE (-2125 910);
FORCEPROP 2 LASTPROP $XRERR UNIQUE?
J 0
(-2415 900);
DISPLAY 0.638298 (-2415 900);
PAINT MONO (-2415 900);
DISPLAY INVISIBLE (-2415 900);
WIRE 16 -1 (-2175 1000)(-1325 1000);
FORCEPROP 2 LAST SIG_NAME TP_CH_B_DIMM_B1_RFU_2
J 0
(-2125 1010);
DISPLAY 0.617021 (-2125 1010);
PAINT ORANGE (-2125 1010);
FORCEPROP 2 LASTPROP $XRERR UNIQUE?
J 0
(-2415 1000);
DISPLAY 0.638298 (-2415 1000);
PAINT MONO (-2415 1000);
DISPLAY INVISIBLE (-2415 1000);
WIRE 16 -1 (-2175 800)(-1325 800);
FORCEPROP 2 LAST SIG_NAME FM_ADR_COMPLETE_ABC_N
J 0
(-2125 810);
DISPLAY 0.617021 (-2125 810);
PAINT ORANGE (-2125 810);
WIRE 16 -1 (-2175 1200)(-1325 1200);
FORCEPROP 2 LAST SIG_NAME SMB_DDR_ABC_VPP_SCL
J 0
(-2135 1210);
DISPLAY 0.617021 (-2135 1210);
PAINT ORANGE (-2135 1210);
WIRE 16 -1 (-1325 1250)(-2175 1250);
WIRE 16 -1 (-1325 1600)(-2350 1600);
FORCEPROP 2 LAST SIG_NAME M_B_ALERT_N
J 0
(-2300 1610);
DISPLAY 0.617021 (-2300 1610);
PAINT ORANGE (-2300 1610);
WIRE 16 -1 (-1325 1550)(-2325 1550);
FORCEPROP 2 LAST SIG_NAME M_B_ACT_N
J 0
(-2275 1560);
DISPLAY 0.617021 (-2275 1560);
PAINT ORANGE (-2275 1560);
WIRE 16 -1 (-1775 1650)(-1325 1650);
WIRE 16 -1 (-1775 1650)(-1775 1950);
WIRE 16 -1 (-1775 1950)(-2500 1950);
FORCEPROP 2 LAST SIG_NAME FM_DIMM_EVENT_COD_N
J 0
(-2506 1972);
DISPLAY 0.617021 (-2506 1972);
PAINT ORANGE (-2506 1972);
WIRE 16 -1 (-1325 1850)(-1525 1850);
WIRE 16 -1 (-1325 1900)(-1525 1900);
WIRE 16 -1 (-1325 1950)(-1525 1950);
WIRE 16 -1 (-1325 2000)(-1525 2000);
WIRE 16 -1 (-125 1350)(-325 1350);
WIRE 16 -1 (-125 1300)(-325 1300);
WIRE 16 -1 (-125 1250)(-325 1250);
WIRE 16 -1 (-125 1200)(-325 1200);
WIRE 16 -1 (-125 1100)(-325 1100);
WIRE 16 -1 (-125 1400)(-325 1400);
WIRE 16 -1 (-125 1450)(-325 1450);
WIRE 16 -1 (-125 1500)(-325 1500);
WIRE 16 -1 (-125 1150)(-325 1150);
WIRE 16 -1 (-125 1950)(-325 1950);
WIRE 16 -1 (-125 1850)(-325 1850);
WIRE 16 -1 (-125 1550)(-325 1550);
WIRE 16 -1 (-125 1600)(-325 1600);
WIRE 16 -1 (-125 1650)(-325 1650);
WIRE 16 -1 (-125 1700)(-325 1700);
WIRE 16 -1 (-125 1750)(-325 1750);
WIRE 16 -1 (-125 1800)(-325 1800);
WIRE 16 -1 (-125 1900)(-325 1900);
WIRE 16 -1 (-125 2000)(-325 2000);
WIRE 16 -1 (-1675 1750)(-1675 2200);
WIRE 16 -1 (-1325 1750)(-1675 1750);
WIRE 16 -1 (-1675 2200)(-2175 2200);
FORCEPROP 2 LAST SIG_NAME M_B_PAR
J 0
(-2150 2210);
DISPLAY 0.617021 (-2150 2210);
PAINT ORANGE (-2150 2210);
WIRE 16 -1 (-1725 1700)(-1725 2150);
WIRE 16 -1 (-1325 1700)(-1725 1700);
WIRE 16 -1 (-1725 2150)(-2175 2150);
FORCEPROP 2 LAST SIG_NAME M_ABC_RST_N
J 0
(-2150 2160);
DISPLAY 0.617021 (-2150 2160);
PAINT ORANGE (-2150 2160);
WIRE 16 -1 (-1325 2900)(-1725 2900);
WIRE 16 -1 (-1325 3000)(-1725 3000);
WIRE 16 -1 (-1325 2200)(-1525 2200);
WIRE 16 -1 (-1325 2050)(-1525 2050);
WIRE 16 -1 (-1325 2100)(-1525 2100);
WIRE 16 -1 (-1325 2150)(-1525 2150);
WIRE 16 -1 (-1325 2300)(-1525 2300);
WIRE 16 -1 (-1325 2450)(-1525 2450);
WIRE 16 -1 (-1325 2350)(-1525 2350);
WIRE 16 -1 (-1325 2500)(-1525 2500);
WIRE 16 -1 (-1325 2600)(-1525 2600);
WIRE 16 -1 (-1325 2650)(-1525 2650);
WIRE 16 -1 (-1325 2700)(-1525 2700);
WIRE 16 -1 (-1325 2750)(-1525 2750);
WIRE 16 -1 (-1475 2850)(-1475 2800);
WIRE 16 -1 (-1475 2850)(-2175 2850);
FORCEPROP 2 LAST SIG_NAME M_B_C<2>
J 0
(-2125 2860);
DISPLAY 0.617021 (-2125 2860);
PAINT ORANGE (-2125 2860);
WIRE 16 -1 (-1475 2800)(-1325 2800);
WIRE 16 -1 (-1325 3050)(-1525 3050);
WIRE 16 -1 (-1325 2950)(-1525 2950);
WIRE 16 -1 (-1325 3250)(-1525 3250);
WIRE 16 -1 (-1325 3200)(-1525 3200);
WIRE 16 -1 (-1325 3150)(-1525 3150);
WIRE 16 -1 (-1325 3300)(-1525 3300);
WIRE 16 -1 (-1325 3500)(-1525 3500);
WIRE 16 -1 (-1325 3550)(-1525 3550);
WIRE 16 -1 (-1325 3450)(-1525 3450);
WIRE 16 -1 (-1325 3400)(-1525 3400);
WIRE 16 -1 (-1325 3650)(-1525 3650);
WIRE 16 -1 (-1325 3800)(-1525 3800);
WIRE 16 -1 (-1325 3750)(-1525 3750);
WIRE 16 -1 (-1325 3700)(-1525 3700);
WIRE 16 -1 (-1325 3600)(-1525 3600);
WIRE 16 -1 (-1325 3950)(-1525 3950);
WIRE 16 -1 (-1325 3900)(-1525 3900);
WIRE 16 -1 (-1325 3850)(-1525 3850);
WIRE 16 -1 (-1325 4050)(-1525 4050);
WIRE 16 -1 (-1325 4000)(-1525 4000);
WIRE 16 -1 (-125 2400)(-325 2400);
WIRE 16 -1 (-125 2450)(-325 2450);
WIRE 16 -1 (-125 2050)(-325 2050);
WIRE 16 -1 (-125 2100)(-325 2100);
WIRE 16 -1 (-125 2150)(-325 2150);
WIRE 16 -1 (-125 2200)(-325 2200);
WIRE 16 -1 (-125 2250)(-325 2250);
WIRE 16 -1 (-125 2300)(-325 2300);
WIRE 16 -1 (-125 2350)(-325 2350);
WIRE 16 -1 (-125 2500)(-325 2500);
WIRE 16 -1 (-125 2550)(-325 2550);
WIRE 16 -1 (-125 3000)(-325 3000);
WIRE 16 -1 (-125 2900)(-325 2900);
WIRE 16 -1 (-125 2850)(-325 2850);
WIRE 16 -1 (-125 2600)(-325 2600);
WIRE 16 -1 (-125 2650)(-325 2650);
WIRE 16 -1 (-125 2700)(-325 2700);
WIRE 16 -1 (-125 2750)(-325 2750);
WIRE 16 -1 (-125 2800)(-325 2800);
WIRE 16 -1 (-125 2950)(-325 2950);
WIRE 16 -1 (-125 3050)(-325 3050);
WIRE 16 -1 (-125 3450)(-325 3450);
WIRE 16 -1 (-125 3500)(-325 3500);
WIRE 16 -1 (-125 3550)(-325 3550);
WIRE 16 -1 (-125 3100)(-325 3100);
WIRE 16 -1 (-125 3150)(-325 3150);
WIRE 16 -1 (-125 3200)(-325 3200);
WIRE 16 -1 (-125 3250)(-325 3250);
WIRE 16 -1 (-125 3300)(-325 3300);
WIRE 16 -1 (-125 3350)(-325 3350);
WIRE 16 -1 (-125 3400)(-325 3400);
WIRE 16 -1 (-125 3600)(-325 3600);
WIRE 16 -1 (-125 3650)(-325 3650);
WIRE 16 -1 (-125 3700)(-325 3700);
WIRE 16 -1 (-125 3750)(-325 3750);
WIRE 16 -1 (-125 3800)(-325 3800);
WIRE 16 -1 (-125 4000)(-325 4000);
WIRE 16 -1 (-125 3950)(-325 3950);
WIRE 16 -1 (-125 3850)(-325 3850);
WIRE 16 -1 (-125 3900)(-325 3900);
WIRE 16 -1 (-125 4050)(-325 4050);
WIRE 16 -1 (-1325 4200)(-1525 4200);
WIRE 16 -1 (-1325 4150)(-1525 4150);
WIRE 16 -1 (-1325 4100)(-1525 4100);
WIRE 16 -1 (-1325 4250)(-1525 4250);
WIRE 16 -1 (-125 4100)(-325 4100);
WIRE 16 -1 (-125 4150)(-325 4150);
WIRE 16 -1 (-125 4200)(-325 4200);
WIRE 16 -1 (-125 4250)(-325 4250);
WIRE 16 -1 (2075 3050)(2475 3050);
WIRE 16 -1 (2075 3300)(2275 3300);
WIRE 16 -1 (2075 3200)(2275 3200);
WIRE 16 -1 (2075 3100)(2275 3100);
WIRE 16 -1 (2275 3500)(2075 3500);
WIRE 16 -1 (2275 3400)(2075 3400);
WIRE 16 -1 (2475 3550)(2075 3550);
WIRE 16 -1 (2475 3450)(2075 3450);
WIRE 16 -1 (2475 3350)(2075 3350);
WIRE 16 -1 (2075 3250)(2475 3250);
WIRE 16 -1 (2075 3150)(2475 3150);
WIRE 16 -1 (2275 3800)(2075 3800);
WIRE 16 -1 (2275 3700)(2075 3700);
WIRE 16 -1 (2275 3600)(2075 3600);
WIRE 16 -1 (2275 4000)(2075 4000);
WIRE 16 -1 (2275 3900)(2075 3900);
WIRE 16 -1 (2475 3950)(2075 3950);
WIRE 16 -1 (2475 3850)(2075 3850);
WIRE 16 -1 (2475 3750)(2075 3750);
WIRE 16 -1 (2475 3650)(2075 3650);
WIRE 16 -1 (2475 4050)(2075 4050);
WIRE 16 -1 (2275 4300)(2075 4300);
WIRE 16 -1 (2275 4200)(2075 4200);
WIRE 16 -1 (2275 4100)(2075 4100);
WIRE 16 -1 (2275 4600)(2075 4600);
WIRE 16 -1 (2275 4500)(2075 4500);
WIRE 16 -1 (2275 4400)(2075 4400);
WIRE 16 -1 (2475 4550)(2075 4550);
WIRE 16 -1 (2475 4450)(2075 4450);
WIRE 16 -1 (2475 4350)(2075 4350);
WIRE 16 -1 (2475 4250)(2075 4250);
WIRE 16 -1 (2475 4150)(2075 4150);
WIRE 16 -1 (2275 4800)(2075 4800);
WIRE 16 -1 (2275 4700)(2075 4700);
WIRE 16 -1 (2475 4750)(2075 4750);
WIRE 16 -1 (2475 4650)(2075 4650);
DOT 1 (975 2050);
DOT 1 (2725 2600);
DOT 1 (2725 2500);
DOT 1 (975 850);
DOT 1 (975 900);
DOT 1 (-1475 1350);
DOT 1 (-1475 1450);
DOT 1 (-2975 1100);
DOT 1 (975 950);
DOT 1 (975 1000);
DOT 1 (975 1050);
DOT 1 (975 1150);
DOT 1 (975 1100);
DOT 1 (975 1200);
DOT 1 (975 1250);
DOT 1 (975 1300);
DOT 1 (975 1400);
DOT 1 (975 1350);
DOT 1 (975 1450);
DOT 1 (975 1500);
DOT 1 (975 1550);
DOT 1 (975 1650);
DOT 1 (975 1600);
DOT 1 (975 1700);
DOT 1 (975 1750);
DOT 1 (975 1800);
DOT 1 (975 1900);
DOT 1 (975 1850);
DOT 1 (975 2200);
DOT 1 (975 2000);
DOT 1 (975 2350);
DOT 1 (975 2400);
DOT 1 (975 2450);
DOT 1 (975 2500);
DOT 1 (2725 1100);
DOT 1 (2725 1150);
DOT 1 (2725 1300);
DOT 1 (2725 1200);
DOT 1 (2725 1250);
DOT 1 (2725 1350);
DOT 1 (2725 1400);
DOT 1 (2725 1450);
DOT 1 (2725 1550);
DOT 1 (2725 1500);
DOT 1 (2725 1600);
DOT 1 (2725 1650);
DOT 1 (2725 1700);
DOT 1 (2375 2500);
DOT 1 (2725 1800);
DOT 1 (2725 1750);
DOT 1 (2725 1950);
DOT 1 (2725 1900);
DOT 1 (2725 1850);
DOT 1 (2725 2000);
DOT 1 (2725 2050);
DOT 1 (2725 2200);
DOT 1 (2725 2100);
DOT 1 (2725 2150);
DOT 1 (2725 2300);
DOT 1 (2725 2250);
DOT 1 (2725 2350);
DOT 1 (2725 2450);
DOT 1 (2725 2400);
DOT 1 (2725 2550);
DOT 1 (2725 2700);
DOT 1 (2725 2650);
DOT 1 (2725 2800);
DOT 1 (2725 2750);
DOT 1 (2725 2850);
DOT 1 (2725 2900);
DOT 1 (2725 2950);
DOT 1 (2725 3100);
DOT 1 (2725 3050);
DOT 1 (2725 3000);
DOT 1 (2725 3150);
DOT 1 (2725 3200);
DOT 1 (2725 3250);
DOT 1 (2725 3300);
DOT 1 (2725 3350);
DOT 1 (4125 1100);
DOT 1 (4125 1150);
DOT 1 (4125 1300);
DOT 1 (4125 1250);
DOT 1 (4125 1200);
DOT 1 (4125 1350);
DOT 1 (4125 1400);
DOT 1 (4125 1450);
DOT 1 (4125 1550);
DOT 1 (4125 1500);
DOT 1 (4125 1600);
DOT 1 (4125 1650);
DOT 1 (4125 1700);
DOT 1 (4125 1800);
DOT 1 (4125 1750);
DOT 1 (4125 1950);
DOT 1 (4125 1900);
DOT 1 (4125 1850);
DOT 1 (4125 2000);
DOT 1 (4125 2050);
DOT 1 (4125 2200);
DOT 1 (4125 2150);
DOT 1 (4125 2100);
DOT 1 (4125 2300);
DOT 1 (4125 2250);
DOT 1 (4125 2350);
DOT 1 (4125 2450);
DOT 1 (4125 2400);
DOT 1 (4125 2500);
DOT 1 (4125 2550);
DOT 1 (4125 2600);
DOT 1 (4125 2700);
DOT 1 (4125 2650);
DOT 1 (4125 2800);
DOT 1 (4125 2750);
DOT 1 (4125 2850);
DOT 1 (4125 2900);
DOT 1 (4125 2950);
DOT 1 (4125 3100);
DOT 1 (4125 3050);
DOT 1 (4125 3000);
DOT 1 (4125 3150);
DOT 1 (4125 3200);
DOT 1 (4125 3250);
DOT 1 (4125 3300);
DOT 1 (4125 3350);
DOT 1 (975 1950);
FORCENOTE
SMBUS ADDR: 0XA6
(-3692 387) 0;
DISPLAY LEFT (-3692 387);
DISPLAY 1.957447 (-3692 387);
PAINT PURPLE (-3692 387);
FORCENOTE
PLACE CAP NEAR DIMM CONNECTOR
(-3679 550) 0;
DISPLAY LEFT (-3679 550);
DISPLAY 1.595745 (-3679 550);
PAINT PURPLE (-3679 550);
QUIT
